FILE_TYPE = MACRO_DRAWING;
SET COLOR_WIRE YELLOW;
SET COLOR_PROP ORANGE;
SET COLOR_DOT WHITE;
SET COLOR_ARC YELLOW;
SET COLOR_BODY GREEN;
SET COLOR_NOTE PURPLE;
SET PROP_DISPLAY VALUE;
SET PAGE_NUMBER P59;
FORCEADD GENOA_SP5..34
(-7975 3500);
FORCEPROP 1 LAST LOCATION U26
J 0
(-8375 6675);
DISPLAY 0.489362 (-8375 6675);
PAINT SKYBLUE (-8375 6675);
FORCEPROP 0 LAST $SEC 34
J 0
(-8350 6900);
DISPLAY 0.680851 (-8350 6900);
PAINT MONO (-8350 6900);
DISPLAY INVISIBLE (-8350 6900);
FORCEPROP 0 LAST CDS_SEC 34
J 0
(-8350 6900);
DISPLAY 1.021277 (-8350 6900);
DISPLAY INVISIBLE (-8350 6900);
FORCEPROP 0 LASTPIN (-8525 6450) $PN BL26
J 2
(-8535 6460);
DISPLAY 0.489362 (-8535 6460);
PAINT MONO (-8535 6460);
FORCEPROP 0 LASTPIN (-8525 6400) $PN BL28
J 2
(-8535 6410);
DISPLAY 0.489362 (-8535 6410);
PAINT MONO (-8535 6410);
FORCEPROP 0 LASTPIN (-8525 6350) $PN BL49
J 2
(-8535 6360);
DISPLAY 0.489362 (-8535 6360);
PAINT MONO (-8535 6360);
FORCEPROP 0 LASTPIN (-8525 6300) $PN BL51
J 2
(-8535 6310);
DISPLAY 0.489362 (-8535 6310);
PAINT MONO (-8535 6310);
FORCEPROP 0 LASTPIN (-8525 6250) $PN BL53
J 2
(-8535 6260);
DISPLAY 0.489362 (-8535 6260);
PAINT MONO (-8535 6260);
FORCEPROP 0 LASTPIN (-8525 6200) $PN BL56
J 2
(-8535 6210);
DISPLAY 0.489362 (-8535 6210);
PAINT MONO (-8535 6210);
FORCEPROP 0 LASTPIN (-8525 6150) $PN BL58
J 2
(-8535 6160);
DISPLAY 0.489362 (-8535 6160);
PAINT MONO (-8535 6160);
FORCEPROP 0 LASTPIN (-8525 6100) $PN BL61
J 2
(-8535 6110);
DISPLAY 0.489362 (-8535 6110);
PAINT MONO (-8535 6110);
FORCEPROP 0 LASTPIN (-8525 6050) $PN BL63
J 2
(-8535 6060);
DISPLAY 0.489362 (-8535 6060);
PAINT MONO (-8535 6060);
FORCEPROP 0 LASTPIN (-8525 6000) $PN BL65
J 2
(-8535 6010);
DISPLAY 0.489362 (-8535 6010);
PAINT MONO (-8535 6010);
FORCEPROP 0 LASTPIN (-8525 5950) $PN BL68
J 2
(-8535 5960);
DISPLAY 0.489362 (-8535 5960);
PAINT MONO (-8535 5960);
FORCEPROP 0 LASTPIN (-8525 5900) $PN BL70
J 2
(-8535 5910);
DISPLAY 0.489362 (-8535 5910);
PAINT MONO (-8535 5910);
FORCEPROP 0 LASTPIN (-8525 5850) $PN BL72
J 2
(-8535 5860);
DISPLAY 0.489362 (-8535 5860);
PAINT MONO (-8535 5860);
FORCEPROP 0 LASTPIN (-8525 5800) $PN BL75
J 2
(-8535 5810);
DISPLAY 0.489362 (-8535 5810);
PAINT MONO (-8535 5810);
FORCEPROP 0 LASTPIN (-8525 5750) $PN BM3
J 2
(-8535 5760);
DISPLAY 0.489362 (-8535 5760);
PAINT MONO (-8535 5760);
FORCEPROP 0 LASTPIN (-8525 5700) $PN BM8
J 2
(-8535 5710);
DISPLAY 0.489362 (-8535 5710);
PAINT MONO (-8535 5710);
FORCEPROP 0 LASTPIN (-8525 5650) $PN BM10
J 2
(-8535 5660);
DISPLAY 0.489362 (-8535 5660);
PAINT MONO (-8535 5660);
FORCEPROP 0 LASTPIN (-8525 5600) $PN BM15
J 2
(-8535 5610);
DISPLAY 0.489362 (-8535 5610);
PAINT MONO (-8535 5610);
FORCEPROP 0 LASTPIN (-8525 5550) $PN BM17
J 2
(-8535 5560);
DISPLAY 0.489362 (-8535 5560);
PAINT MONO (-8535 5560);
FORCEPROP 0 LASTPIN (-8525 5500) $PN BM23
J 2
(-8535 5510);
DISPLAY 0.489362 (-8535 5510);
PAINT MONO (-8535 5510);
FORCEPROP 0 LASTPIN (-8525 5450) $PN BM25
J 2
(-8535 5460);
DISPLAY 0.489362 (-8535 5460);
PAINT MONO (-8535 5460);
FORCEPROP 0 LASTPIN (-8525 5400) $PN BM27
J 2
(-8535 5410);
DISPLAY 0.489362 (-8535 5410);
PAINT MONO (-8535 5410);
FORCEPROP 0 LASTPIN (-8525 5350) $PN BM29
J 2
(-8535 5360);
DISPLAY 0.489362 (-8535 5360);
PAINT MONO (-8535 5360);
FORCEPROP 0 LASTPIN (-8525 5300) $PN BM31
J 2
(-8535 5310);
DISPLAY 0.489362 (-8535 5310);
PAINT MONO (-8535 5310);
FORCEPROP 0 LASTPIN (-8525 5250) $PN BM33
J 2
(-8535 5260);
DISPLAY 0.489362 (-8535 5260);
PAINT MONO (-8535 5260);
FORCEPROP 0 LASTPIN (-8525 5200) $PN BM35
J 2
(-8535 5210);
DISPLAY 0.489362 (-8535 5210);
PAINT MONO (-8535 5210);
FORCEPROP 0 LASTPIN (-8525 5150) $PN BM37
J 2
(-8535 5160);
DISPLAY 0.489362 (-8535 5160);
PAINT MONO (-8535 5160);
FORCEPROP 0 LASTPIN (-8525 5100) $PN BM40
J 2
(-8535 5110);
DISPLAY 0.489362 (-8535 5110);
PAINT MONO (-8535 5110);
FORCEPROP 0 LASTPIN (-8525 5050) $PN BM42
J 2
(-8535 5060);
DISPLAY 0.489362 (-8535 5060);
PAINT MONO (-8535 5060);
FORCEPROP 0 LASTPIN (-8525 5000) $PN BM44
J 2
(-8535 5010);
DISPLAY 0.489362 (-8535 5010);
PAINT MONO (-8535 5010);
FORCEPROP 0 LASTPIN (-8525 4950) $PN BM46
J 2
(-8535 4960);
DISPLAY 0.489362 (-8535 4960);
PAINT MONO (-8535 4960);
FORCEPROP 0 LASTPIN (-8525 4900) $PN BM48
J 2
(-8535 4910);
DISPLAY 0.489362 (-8535 4910);
PAINT MONO (-8535 4910);
FORCEPROP 0 LASTPIN (-8525 4850) $PN BM50
J 2
(-8535 4860);
DISPLAY 0.489362 (-8535 4860);
PAINT MONO (-8535 4860);
FORCEPROP 0 LASTPIN (-8525 4800) $PN BM52
J 2
(-8535 4810);
DISPLAY 0.489362 (-8535 4810);
PAINT MONO (-8535 4810);
FORCEPROP 0 LASTPIN (-8525 4750) $PN BM54
J 2
(-8535 4760);
DISPLAY 0.489362 (-8535 4760);
PAINT MONO (-8535 4760);
FORCEPROP 0 LASTPIN (-8525 4700) $PN BM59
J 2
(-8535 4710);
DISPLAY 0.489362 (-8535 4710);
PAINT MONO (-8535 4710);
FORCEPROP 0 LASTPIN (-8525 4650) $PN BM61
J 2
(-8535 4660);
DISPLAY 0.489362 (-8535 4660);
PAINT MONO (-8535 4660);
FORCEPROP 0 LASTPIN (-8525 4600) $PN BM66
J 2
(-8535 4610);
DISPLAY 0.489362 (-8535 4610);
PAINT MONO (-8535 4610);
FORCEPROP 0 LASTPIN (-8525 4550) $PN BM68
J 2
(-8535 4560);
DISPLAY 0.489362 (-8535 4560);
PAINT MONO (-8535 4560);
FORCEPROP 0 LASTPIN (-8525 4500) $PN BM73
J 2
(-8535 4510);
DISPLAY 0.489362 (-8535 4510);
PAINT MONO (-8535 4510);
FORCEPROP 0 LASTPIN (-8525 4450) $PN BN1
J 2
(-8535 4460);
DISPLAY 0.489362 (-8535 4460);
PAINT MONO (-8535 4460);
FORCEPROP 0 LASTPIN (-8525 4400) $PN BN4
J 2
(-8535 4410);
DISPLAY 0.489362 (-8535 4410);
PAINT MONO (-8535 4410);
FORCEPROP 0 LASTPIN (-8525 4350) $PN BN6
J 2
(-8535 4360);
DISPLAY 0.489362 (-8535 4360);
PAINT MONO (-8535 4360);
FORCEPROP 0 LASTPIN (-8525 4300) $PN BN8
J 2
(-8535 4310);
DISPLAY 0.489362 (-8535 4310);
PAINT MONO (-8535 4310);
FORCEPROP 0 LASTPIN (-8525 4250) $PN BN11
J 2
(-8535 4260);
DISPLAY 0.489362 (-8535 4260);
PAINT MONO (-8535 4260);
FORCEPROP 0 LASTPIN (-8525 4200) $PN BN13
J 2
(-8535 4210);
DISPLAY 0.489362 (-8535 4210);
PAINT MONO (-8535 4210);
FORCEPROP 0 LASTPIN (-8525 4150) $PN BN15
J 2
(-8535 4160);
DISPLAY 0.489362 (-8535 4160);
PAINT MONO (-8535 4160);
FORCEPROP 0 LASTPIN (-8525 4100) $PN BN18
J 2
(-8535 4110);
DISPLAY 0.489362 (-8535 4110);
PAINT MONO (-8535 4110);
FORCEPROP 0 LASTPIN (-8525 4050) $PN BN20
J 2
(-8535 4060);
DISPLAY 0.489362 (-8535 4060);
PAINT MONO (-8535 4060);
FORCEPROP 0 LASTPIN (-8525 4000) $PN BN22
J 2
(-8535 4010);
DISPLAY 0.489362 (-8535 4010);
PAINT MONO (-8535 4010);
FORCEPROP 0 LASTPIN (-8525 3950) $PN BN24
J 2
(-8535 3960);
DISPLAY 0.489362 (-8535 3960);
PAINT MONO (-8535 3960);
FORCEPROP 0 LASTPIN (-8525 3900) $PN BN26
J 2
(-8535 3910);
DISPLAY 0.489362 (-8535 3910);
PAINT MONO (-8535 3910);
FORCEPROP 0 LASTPIN (-8525 3850) $PN BN28
J 2
(-8535 3860);
DISPLAY 0.489362 (-8535 3860);
PAINT MONO (-8535 3860);
FORCEPROP 0 LASTPIN (-8525 3800) $PN BN30
J 2
(-8535 3810);
DISPLAY 0.489362 (-8535 3810);
PAINT MONO (-8535 3810);
FORCEPROP 0 LASTPIN (-8525 3750) $PN BN32
J 2
(-8535 3760);
DISPLAY 0.489362 (-8535 3760);
PAINT MONO (-8535 3760);
FORCEPROP 0 LASTPIN (-8525 3700) $PN BN34
J 2
(-8535 3710);
DISPLAY 0.489362 (-8535 3710);
PAINT MONO (-8535 3710);
FORCEPROP 0 LASTPIN (-8525 3650) $PN BN36
J 2
(-8535 3660);
DISPLAY 0.489362 (-8535 3660);
PAINT MONO (-8535 3660);
FORCEPROP 0 LASTPIN (-8525 3600) $PN BN41
J 2
(-8535 3610);
DISPLAY 0.489362 (-8535 3610);
PAINT MONO (-8535 3610);
FORCEPROP 0 LASTPIN (-8525 3550) $PN BN43
J 2
(-8535 3560);
DISPLAY 0.489362 (-8535 3560);
PAINT MONO (-8535 3560);
FORCEPROP 0 LASTPIN (-8525 3500) $PN BN45
J 2
(-8535 3510);
DISPLAY 0.489362 (-8535 3510);
PAINT MONO (-8535 3510);
FORCEPROP 0 LASTPIN (-8525 3450) $PN BN47
J 2
(-8535 3460);
DISPLAY 0.489362 (-8535 3460);
PAINT MONO (-8535 3460);
FORCEPROP 0 LASTPIN (-8525 3400) $PN BN49
J 2
(-8535 3410);
DISPLAY 0.489362 (-8535 3410);
PAINT MONO (-8535 3410);
FORCEPROP 0 LASTPIN (-8525 3350) $PN BN51
J 2
(-8535 3360);
DISPLAY 0.489362 (-8535 3360);
PAINT MONO (-8535 3360);
FORCEPROP 0 LASTPIN (-8525 3300) $PN BN53
J 2
(-8535 3310);
DISPLAY 0.489362 (-8535 3310);
PAINT MONO (-8535 3310);
FORCEPROP 0 LASTPIN (-8525 3250) $PN BN56
J 2
(-8535 3260);
DISPLAY 0.489362 (-8535 3260);
PAINT MONO (-8535 3260);
FORCEPROP 0 LASTPIN (-8525 3200) $PN BN58
J 2
(-8535 3210);
DISPLAY 0.489362 (-8535 3210);
PAINT MONO (-8535 3210);
FORCEPROP 0 LASTPIN (-8525 3150) $PN BN61
J 2
(-8535 3160);
DISPLAY 0.489362 (-8535 3160);
PAINT MONO (-8535 3160);
FORCEPROP 0 LASTPIN (-8525 3100) $PN BN63
J 2
(-8535 3110);
DISPLAY 0.489362 (-8535 3110);
PAINT MONO (-8535 3110);
FORCEPROP 0 LASTPIN (-8525 3050) $PN BN65
J 2
(-8535 3060);
DISPLAY 0.489362 (-8535 3060);
PAINT MONO (-8535 3060);
FORCEPROP 0 LASTPIN (-8525 3000) $PN BN68
J 2
(-8535 3010);
DISPLAY 0.489362 (-8535 3010);
PAINT MONO (-8535 3010);
FORCEPROP 0 LASTPIN (-8525 2950) $PN BN70
J 2
(-8535 2960);
DISPLAY 0.489362 (-8535 2960);
PAINT MONO (-8535 2960);
FORCEPROP 0 LASTPIN (-8525 2900) $PN BN72
J 2
(-8535 2910);
DISPLAY 0.489362 (-8535 2910);
PAINT MONO (-8535 2910);
FORCEPROP 0 LASTPIN (-8525 2850) $PN BN75
J 2
(-8535 2860);
DISPLAY 0.489362 (-8535 2860);
PAINT MONO (-8535 2860);
FORCEPROP 0 LASTPIN (-8525 2800) $PN BP3
J 2
(-8535 2810);
DISPLAY 0.489362 (-8535 2810);
PAINT MONO (-8535 2810);
FORCEPROP 0 LASTPIN (-8525 2750) $PN BP5
J 2
(-8535 2760);
DISPLAY 0.489362 (-8535 2760);
PAINT MONO (-8535 2760);
FORCEPROP 0 LASTPIN (-8525 2700) $PN BP8
J 2
(-8535 2710);
DISPLAY 0.489362 (-8535 2710);
PAINT MONO (-8535 2710);
FORCEPROP 0 LASTPIN (-8525 2650) $PN BP10
J 2
(-8535 2660);
DISPLAY 0.489362 (-8535 2660);
PAINT MONO (-8535 2660);
FORCEPROP 0 LASTPIN (-8525 2600) $PN BP12
J 2
(-8535 2610);
DISPLAY 0.489362 (-8535 2610);
PAINT MONO (-8535 2610);
FORCEPROP 0 LASTPIN (-8525 2550) $PN BP15
J 2
(-8535 2560);
DISPLAY 0.489362 (-8535 2560);
PAINT MONO (-8535 2560);
FORCEPROP 0 LASTPIN (-8525 2500) $PN BP17
J 2
(-8535 2510);
DISPLAY 0.489362 (-8535 2510);
PAINT MONO (-8535 2510);
FORCEPROP 0 LASTPIN (-8525 2450) $PN BP19
J 2
(-8535 2460);
DISPLAY 0.489362 (-8535 2460);
PAINT MONO (-8535 2460);
FORCEPROP 0 LASTPIN (-8525 2400) $PN BP23
J 2
(-8535 2410);
DISPLAY 0.489362 (-8535 2410);
PAINT MONO (-8535 2410);
FORCEPROP 0 LASTPIN (-8525 2350) $PN BP25
J 2
(-8535 2360);
DISPLAY 0.489362 (-8535 2360);
PAINT MONO (-8535 2360);
FORCEPROP 0 LASTPIN (-8525 2300) $PN BP27
J 2
(-8535 2310);
DISPLAY 0.489362 (-8535 2310);
PAINT MONO (-8535 2310);
FORCEPROP 0 LASTPIN (-8525 2250) $PN BP29
J 2
(-8535 2260);
DISPLAY 0.489362 (-8535 2260);
PAINT MONO (-8535 2260);
FORCEPROP 0 LASTPIN (-8525 2200) $PN BP31
J 2
(-8535 2210);
DISPLAY 0.489362 (-8535 2210);
PAINT MONO (-8535 2210);
FORCEPROP 0 LASTPIN (-8525 2150) $PN BP33
J 2
(-8535 2160);
DISPLAY 0.489362 (-8535 2160);
PAINT MONO (-8535 2160);
FORCEPROP 0 LASTPIN (-8525 2100) $PN BP35
J 2
(-8535 2110);
DISPLAY 0.489362 (-8535 2110);
PAINT MONO (-8535 2110);
FORCEPROP 0 LASTPIN (-8525 2050) $PN BP37
J 2
(-8535 2060);
DISPLAY 0.489362 (-8535 2060);
PAINT MONO (-8535 2060);
FORCEPROP 0 LASTPIN (-8525 2000) $PN BP40
J 2
(-8535 2010);
DISPLAY 0.489362 (-8535 2010);
PAINT MONO (-8535 2010);
FORCEPROP 0 LASTPIN (-8525 1950) $PN BP42
J 2
(-8535 1960);
DISPLAY 0.489362 (-8535 1960);
PAINT MONO (-8535 1960);
FORCEPROP 0 LASTPIN (-8525 1900) $PN BP44
J 2
(-8535 1910);
DISPLAY 0.489362 (-8535 1910);
PAINT MONO (-8535 1910);
FORCEPROP 0 LASTPIN (-8525 1850) $PN BP46
J 2
(-8535 1860);
DISPLAY 0.489362 (-8535 1860);
PAINT MONO (-8535 1860);
FORCEPROP 0 LASTPIN (-8525 1800) $PN BP48
J 2
(-8535 1810);
DISPLAY 0.489362 (-8535 1810);
PAINT MONO (-8535 1810);
FORCEPROP 0 LASTPIN (-8525 1750) $PN BP50
J 2
(-8535 1760);
DISPLAY 0.489362 (-8535 1760);
PAINT MONO (-8535 1760);
FORCEPROP 0 LASTPIN (-8525 1700) $PN BP52
J 2
(-8535 1710);
DISPLAY 0.489362 (-8535 1710);
PAINT MONO (-8535 1710);
FORCEPROP 0 LASTPIN (-8525 1650) $PN BP54
J 2
(-8535 1660);
DISPLAY 0.489362 (-8535 1660);
PAINT MONO (-8535 1660);
FORCEPROP 0 LASTPIN (-8525 1600) $PN BP57
J 2
(-8535 1610);
DISPLAY 0.489362 (-8535 1610);
PAINT MONO (-8535 1610);
FORCEPROP 0 LASTPIN (-8525 1550) $PN BP59
J 2
(-8535 1560);
DISPLAY 0.489362 (-8535 1560);
PAINT MONO (-8535 1560);
FORCEPROP 0 LASTPIN (-8525 1500) $PN BP61
J 2
(-8535 1510);
DISPLAY 0.489362 (-8535 1510);
PAINT MONO (-8535 1510);
FORCEPROP 0 LASTPIN (-8525 1450) $PN BP64
J 2
(-8535 1460);
DISPLAY 0.489362 (-8535 1460);
PAINT MONO (-8535 1460);
FORCEPROP 0 LASTPIN (-8525 1400) $PN BP66
J 2
(-8535 1410);
DISPLAY 0.489362 (-8535 1410);
PAINT MONO (-8535 1410);
FORCEPROP 0 LASTPIN (-8525 1350) $PN BP68
J 2
(-8535 1360);
DISPLAY 0.489362 (-8535 1360);
PAINT MONO (-8535 1360);
FORCEPROP 0 LASTPIN (-8525 1300) $PN BP71
J 2
(-8535 1310);
DISPLAY 0.489362 (-8535 1310);
PAINT MONO (-8535 1310);
FORCEPROP 0 LASTPIN (-8525 1250) $PN BP73
J 2
(-8535 1260);
DISPLAY 0.489362 (-8535 1260);
PAINT MONO (-8535 1260);
FORCEPROP 0 LASTPIN (-8525 1200) $PN BR1
J 2
(-8535 1210);
DISPLAY 0.489362 (-8535 1210);
PAINT MONO (-8535 1210);
FORCEPROP 0 LASTPIN (-8525 1150) $PN BR3
J 2
(-8535 1160);
DISPLAY 0.489362 (-8535 1160);
PAINT MONO (-8535 1160);
FORCEPROP 0 LASTPIN (-8525 1100) $PN BR6
J 2
(-8535 1110);
DISPLAY 0.489362 (-8535 1110);
PAINT MONO (-8535 1110);
FORCEPROP 0 LASTPIN (-8525 1050) $PN BR7
J 2
(-8535 1060);
DISPLAY 0.489362 (-8535 1060);
PAINT MONO (-8535 1060);
FORCEPROP 0 LASTPIN (-8525 1000) $PN BR8
J 2
(-8535 1010);
DISPLAY 0.489362 (-8535 1010);
PAINT MONO (-8535 1010);
FORCEPROP 0 LASTPIN (-8525 950) $PN BR10
J 2
(-8535 960);
DISPLAY 0.489362 (-8535 960);
PAINT MONO (-8535 960);
FORCEPROP 0 LASTPIN (-8525 900) $PN BR13
J 2
(-8535 910);
DISPLAY 0.489362 (-8535 910);
PAINT MONO (-8535 910);
FORCEPROP 0 LASTPIN (-8525 850) $PN BR14
J 2
(-8535 860);
DISPLAY 0.489362 (-8535 860);
PAINT MONO (-8535 860);
FORCEPROP 0 LASTPIN (-8525 800) $PN BR15
J 2
(-8535 810);
DISPLAY 0.489362 (-8535 810);
PAINT MONO (-8535 810);
FORCEPROP 0 LASTPIN (-8525 750) $PN BR17
J 2
(-8535 760);
DISPLAY 0.489362 (-8535 760);
PAINT MONO (-8535 760);
FORCEPROP 0 LASTPIN (-8525 700) $PN BR20
J 2
(-8535 710);
DISPLAY 0.489362 (-8535 710);
PAINT MONO (-8535 710);
FORCEPROP 0 LASTPIN (-8525 650) $PN BR21
J 2
(-8535 660);
DISPLAY 0.489362 (-8535 660);
PAINT MONO (-8535 660);
FORCEPROP 0 LASTPIN (-8525 600) $PN BR22
J 2
(-8535 610);
DISPLAY 0.489362 (-8535 610);
PAINT MONO (-8535 610);
FORCEPROP 0 LASTPIN (-8525 550) $PN BR24
J 2
(-8535 560);
DISPLAY 0.489362 (-8535 560);
PAINT MONO (-8535 560);
FORCEPROP 0 LASTPIN (-7425 6450) $PN BR26
J 0
(-7415 6460);
DISPLAY 0.489362 (-7415 6460);
PAINT MONO (-7415 6460);
FORCEPROP 0 LASTPIN (-7425 6400) $PN BR28
J 0
(-7415 6410);
DISPLAY 0.489362 (-7415 6410);
PAINT MONO (-7415 6410);
FORCEPROP 0 LASTPIN (-7425 6350) $PN BR30
J 0
(-7415 6360);
DISPLAY 0.489362 (-7415 6360);
PAINT MONO (-7415 6360);
FORCEPROP 0 LASTPIN (-7425 6300) $PN BR32
J 0
(-7415 6310);
DISPLAY 0.489362 (-7415 6310);
PAINT MONO (-7415 6310);
FORCEPROP 0 LASTPIN (-7425 6250) $PN BR34
J 0
(-7415 6260);
DISPLAY 0.489362 (-7415 6260);
PAINT MONO (-7415 6260);
FORCEPROP 0 LASTPIN (-7425 6200) $PN BR36
J 0
(-7415 6210);
DISPLAY 0.489362 (-7415 6210);
PAINT MONO (-7415 6210);
FORCEPROP 0 LASTPIN (-7425 6150) $PN BR41
J 0
(-7415 6160);
DISPLAY 0.489362 (-7415 6160);
PAINT MONO (-7415 6160);
FORCEPROP 0 LASTPIN (-7425 6100) $PN BR43
J 0
(-7415 6110);
DISPLAY 0.489362 (-7415 6110);
PAINT MONO (-7415 6110);
FORCEPROP 0 LASTPIN (-7425 6050) $PN BR45
J 0
(-7415 6060);
DISPLAY 0.489362 (-7415 6060);
PAINT MONO (-7415 6060);
FORCEPROP 0 LASTPIN (-7425 6000) $PN BR47
J 0
(-7415 6010);
DISPLAY 0.489362 (-7415 6010);
PAINT MONO (-7415 6010);
FORCEPROP 0 LASTPIN (-7425 5950) $PN BR49
J 0
(-7415 5960);
DISPLAY 0.489362 (-7415 5960);
PAINT MONO (-7415 5960);
FORCEPROP 0 LASTPIN (-7425 5900) $PN BR51
J 0
(-7415 5910);
DISPLAY 0.489362 (-7415 5910);
PAINT MONO (-7415 5910);
FORCEPROP 0 LASTPIN (-7425 5850) $PN BR55
J 0
(-7415 5860);
DISPLAY 0.489362 (-7415 5860);
PAINT MONO (-7415 5860);
FORCEPROP 0 LASTPIN (-7425 5800) $PN BR56
J 0
(-7415 5810);
DISPLAY 0.489362 (-7415 5810);
PAINT MONO (-7415 5810);
FORCEPROP 0 LASTPIN (-7425 5750) $PN BR59
J 0
(-7415 5760);
DISPLAY 0.489362 (-7415 5760);
PAINT MONO (-7415 5760);
FORCEPROP 0 LASTPIN (-7425 5700) $PN BR61
J 0
(-7415 5710);
DISPLAY 0.489362 (-7415 5710);
PAINT MONO (-7415 5710);
FORCEPROP 0 LASTPIN (-7425 5650) $PN BR62
J 0
(-7415 5660);
DISPLAY 0.489362 (-7415 5660);
PAINT MONO (-7415 5660);
FORCEPROP 0 LASTPIN (-7425 5600) $PN BR63
J 0
(-7415 5610);
DISPLAY 0.489362 (-7415 5610);
PAINT MONO (-7415 5610);
FORCEPROP 0 LASTPIN (-7425 5550) $PN BR66
J 0
(-7415 5560);
DISPLAY 0.489362 (-7415 5560);
PAINT MONO (-7415 5560);
FORCEPROP 0 LASTPIN (-7425 5500) $PN BR68
J 0
(-7415 5510);
DISPLAY 0.489362 (-7415 5510);
PAINT MONO (-7415 5510);
FORCEPROP 0 LASTPIN (-7425 5450) $PN BR69
J 0
(-7415 5460);
DISPLAY 0.489362 (-7415 5460);
PAINT MONO (-7415 5460);
FORCEPROP 0 LASTPIN (-7425 5400) $PN BR70
J 0
(-7415 5410);
DISPLAY 0.489362 (-7415 5410);
PAINT MONO (-7415 5410);
FORCEPROP 0 LASTPIN (-7425 5350) $PN BR73
J 0
(-7415 5360);
DISPLAY 0.489362 (-7415 5360);
PAINT MONO (-7415 5360);
FORCEPROP 0 LASTPIN (-7425 5300) $PN BR75
J 0
(-7415 5310);
DISPLAY 0.489362 (-7415 5310);
PAINT MONO (-7415 5310);
FORCEPROP 0 LASTPIN (-7425 5250) $PN BT3
J 0
(-7415 5260);
DISPLAY 0.489362 (-7415 5260);
PAINT MONO (-7415 5260);
FORCEPROP 0 LASTPIN (-7425 5200) $PN BT4
J 0
(-7415 5210);
DISPLAY 0.489362 (-7415 5210);
PAINT MONO (-7415 5210);
FORCEPROP 0 LASTPIN (-7425 5150) $PN BT5
J 0
(-7415 5160);
DISPLAY 0.489362 (-7415 5160);
PAINT MONO (-7415 5160);
FORCEPROP 0 LASTPIN (-7425 5100) $PN BT7
J 0
(-7415 5110);
DISPLAY 0.489362 (-7415 5110);
PAINT MONO (-7415 5110);
FORCEPROP 0 LASTPIN (-7425 5050) $PN BT8
J 0
(-7415 5060);
DISPLAY 0.489362 (-7415 5060);
PAINT MONO (-7415 5060);
FORCEPROP 0 LASTPIN (-7425 5000) $PN BT10
J 0
(-7415 5010);
DISPLAY 0.489362 (-7415 5010);
PAINT MONO (-7415 5010);
FORCEPROP 0 LASTPIN (-7425 4950) $PN BT11
J 0
(-7415 4960);
DISPLAY 0.489362 (-7415 4960);
PAINT MONO (-7415 4960);
FORCEPROP 0 LASTPIN (-7425 4900) $PN BT12
J 0
(-7415 4910);
DISPLAY 0.489362 (-7415 4910);
PAINT MONO (-7415 4910);
FORCEPROP 0 LASTPIN (-7425 4850) $PN BT14
J 0
(-7415 4860);
DISPLAY 0.489362 (-7415 4860);
PAINT MONO (-7415 4860);
FORCEPROP 0 LASTPIN (-7425 4800) $PN BT15
J 0
(-7415 4810);
DISPLAY 0.489362 (-7415 4810);
PAINT MONO (-7415 4810);
FORCEPROP 0 LASTPIN (-7425 4750) $PN BT17
J 0
(-7415 4760);
DISPLAY 0.489362 (-7415 4760);
PAINT MONO (-7415 4760);
FORCEPROP 0 LASTPIN (-7425 4700) $PN BT18
J 0
(-7415 4710);
DISPLAY 0.489362 (-7415 4710);
PAINT MONO (-7415 4710);
FORCEPROP 0 LASTPIN (-7425 4650) $PN BT19
J 0
(-7415 4660);
DISPLAY 0.489362 (-7415 4660);
PAINT MONO (-7415 4660);
FORCEPROP 0 LASTPIN (-7425 4600) $PN BT21
J 0
(-7415 4610);
DISPLAY 0.489362 (-7415 4610);
PAINT MONO (-7415 4610);
FORCEPROP 0 LASTPIN (-7425 4550) $PN BT22
J 0
(-7415 4560);
DISPLAY 0.489362 (-7415 4560);
PAINT MONO (-7415 4560);
FORCEPROP 0 LASTPIN (-7425 4500) $PN BT25
J 0
(-7415 4510);
DISPLAY 0.489362 (-7415 4510);
PAINT MONO (-7415 4510);
FORCEPROP 0 LASTPIN (-7425 4450) $PN BT28
J 0
(-7415 4460);
DISPLAY 0.489362 (-7415 4460);
PAINT MONO (-7415 4460);
FORCEPROP 0 LASTPIN (-7425 4400) $PN BT31
J 0
(-7415 4410);
DISPLAY 0.489362 (-7415 4410);
PAINT MONO (-7415 4410);
FORCEPROP 0 LASTPIN (-7425 4350) $PN BT34
J 0
(-7415 4360);
DISPLAY 0.489362 (-7415 4360);
PAINT MONO (-7415 4360);
FORCEPROP 0 LASTPIN (-7425 4300) $PN BT37
J 0
(-7415 4310);
DISPLAY 0.489362 (-7415 4310);
PAINT MONO (-7415 4310);
FORCEPROP 0 LASTPIN (-7425 4250) $PN BT39
J 0
(-7415 4260);
DISPLAY 0.489362 (-7415 4260);
PAINT MONO (-7415 4260);
FORCEPROP 0 LASTPIN (-7425 4200) $PN BT42
J 0
(-7415 4210);
DISPLAY 0.489362 (-7415 4210);
PAINT MONO (-7415 4210);
FORCEPROP 0 LASTPIN (-7425 4150) $PN BT45
J 0
(-7415 4160);
DISPLAY 0.489362 (-7415 4160);
PAINT MONO (-7415 4160);
FORCEPROP 0 LASTPIN (-7425 4100) $PN BT48
J 0
(-7415 4110);
DISPLAY 0.489362 (-7415 4110);
PAINT MONO (-7415 4110);
FORCEPROP 0 LASTPIN (-7425 4050) $PN BT51
J 0
(-7415 4060);
DISPLAY 0.489362 (-7415 4060);
PAINT MONO (-7415 4060);
FORCEPROP 0 LASTPIN (-7425 4000) $PN BT54
J 0
(-7415 4010);
DISPLAY 0.489362 (-7415 4010);
PAINT MONO (-7415 4010);
FORCEPROP 0 LASTPIN (-7425 3950) $PN BT55
J 0
(-7415 3960);
DISPLAY 0.489362 (-7415 3960);
PAINT MONO (-7415 3960);
FORCEPROP 0 LASTPIN (-7425 3900) $PN BT57
J 0
(-7415 3910);
DISPLAY 0.489362 (-7415 3910);
PAINT MONO (-7415 3910);
FORCEPROP 0 LASTPIN (-7425 3850) $PN BT58
J 0
(-7415 3860);
DISPLAY 0.489362 (-7415 3860);
PAINT MONO (-7415 3860);
FORCEPROP 0 LASTPIN (-7425 3800) $PN BT59
J 0
(-7415 3810);
DISPLAY 0.489362 (-7415 3810);
PAINT MONO (-7415 3810);
FORCEPROP 0 LASTPIN (-7425 3750) $PN BT61
J 0
(-7415 3760);
DISPLAY 0.489362 (-7415 3760);
PAINT MONO (-7415 3760);
FORCEPROP 0 LASTPIN (-7425 3700) $PN BT62
J 0
(-7415 3710);
DISPLAY 0.489362 (-7415 3710);
PAINT MONO (-7415 3710);
FORCEPROP 0 LASTPIN (-7425 3650) $PN BT64
J 0
(-7415 3660);
DISPLAY 0.489362 (-7415 3660);
PAINT MONO (-7415 3660);
FORCEPROP 0 LASTPIN (-7425 3600) $PN BT65
J 0
(-7415 3610);
DISPLAY 0.489362 (-7415 3610);
PAINT MONO (-7415 3610);
FORCEPROP 0 LASTPIN (-7425 3550) $PN BT66
J 0
(-7415 3560);
DISPLAY 0.489362 (-7415 3560);
PAINT MONO (-7415 3560);
FORCEPROP 0 LASTPIN (-7425 3500) $PN BT68
J 0
(-7415 3510);
DISPLAY 0.489362 (-7415 3510);
PAINT MONO (-7415 3510);
FORCEPROP 0 LASTPIN (-7425 3450) $PN BT69
J 0
(-7415 3460);
DISPLAY 0.489362 (-7415 3460);
PAINT MONO (-7415 3460);
FORCEPROP 0 LASTPIN (-7425 3400) $PN BT71
J 0
(-7415 3410);
DISPLAY 0.489362 (-7415 3410);
PAINT MONO (-7415 3410);
FORCEPROP 0 LASTPIN (-7425 3350) $PN BT72
J 0
(-7415 3360);
DISPLAY 0.489362 (-7415 3360);
PAINT MONO (-7415 3360);
FORCEPROP 0 LASTPIN (-7425 3300) $PN BT73
J 0
(-7415 3310);
DISPLAY 0.489362 (-7415 3310);
PAINT MONO (-7415 3310);
FORCEPROP 0 LASTPIN (-7425 3250) $PN BU1
J 0
(-7415 3260);
DISPLAY 0.489362 (-7415 3260);
PAINT MONO (-7415 3260);
FORCEPROP 0 LASTPIN (-7425 3200) $PN BU4
J 0
(-7415 3210);
DISPLAY 0.489362 (-7415 3210);
PAINT MONO (-7415 3210);
FORCEPROP 0 LASTPIN (-7425 3150) $PN BU6
J 0
(-7415 3160);
DISPLAY 0.489362 (-7415 3160);
PAINT MONO (-7415 3160);
FORCEPROP 0 LASTPIN (-7425 3100) $PN BU8
J 0
(-7415 3110);
DISPLAY 0.489362 (-7415 3110);
PAINT MONO (-7415 3110);
FORCEPROP 0 LASTPIN (-7425 3050) $PN BU11
J 0
(-7415 3060);
DISPLAY 0.489362 (-7415 3060);
PAINT MONO (-7415 3060);
FORCEPROP 0 LASTPIN (-7425 3000) $PN BU13
J 0
(-7415 3010);
DISPLAY 0.489362 (-7415 3010);
PAINT MONO (-7415 3010);
FORCEPROP 0 LASTPIN (-7425 2950) $PN BU15
J 0
(-7415 2960);
DISPLAY 0.489362 (-7415 2960);
PAINT MONO (-7415 2960);
FORCEPROP 0 LASTPIN (-7425 2900) $PN BU18
J 0
(-7415 2910);
DISPLAY 0.489362 (-7415 2910);
PAINT MONO (-7415 2910);
FORCEPROP 0 LASTPIN (-7425 2850) $PN BU20
J 0
(-7415 2860);
DISPLAY 0.489362 (-7415 2860);
PAINT MONO (-7415 2860);
FORCEPROP 0 LASTPIN (-7425 2800) $PN BU22
J 0
(-7415 2810);
DISPLAY 0.489362 (-7415 2810);
PAINT MONO (-7415 2810);
FORCEPROP 0 LASTPIN (-7425 2750) $PN BU25
J 0
(-7415 2760);
DISPLAY 0.489362 (-7415 2760);
PAINT MONO (-7415 2760);
FORCEPROP 0 LASTPIN (-7425 2700) $PN BU28
J 0
(-7415 2710);
DISPLAY 0.489362 (-7415 2710);
PAINT MONO (-7415 2710);
FORCEPROP 0 LASTPIN (-7425 2650) $PN BU31
J 0
(-7415 2660);
DISPLAY 0.489362 (-7415 2660);
PAINT MONO (-7415 2660);
FORCEPROP 0 LASTPIN (-7425 2600) $PN BU34
J 0
(-7415 2610);
DISPLAY 0.489362 (-7415 2610);
PAINT MONO (-7415 2610);
FORCEPROP 0 LASTPIN (-7425 2550) $PN BU35
J 0
(-7415 2560);
DISPLAY 0.489362 (-7415 2560);
PAINT MONO (-7415 2560);
FORCEPROP 0 LASTPIN (-7425 2500) $PN BU36
J 0
(-7415 2510);
DISPLAY 0.489362 (-7415 2510);
PAINT MONO (-7415 2510);
FORCEPROP 0 LASTPIN (-7425 2450) $PN BU40
J 0
(-7415 2460);
DISPLAY 0.489362 (-7415 2460);
PAINT MONO (-7415 2460);
FORCEPROP 0 LASTPIN (-7425 2400) $PN BU41
J 0
(-7415 2410);
DISPLAY 0.489362 (-7415 2410);
PAINT MONO (-7415 2410);
FORCEPROP 0 LASTPIN (-7425 2350) $PN BU42
J 0
(-7415 2360);
DISPLAY 0.489362 (-7415 2360);
PAINT MONO (-7415 2360);
FORCEPROP 0 LASTPIN (-7425 2300) $PN BU45
J 0
(-7415 2310);
DISPLAY 0.489362 (-7415 2310);
PAINT MONO (-7415 2310);
FORCEPROP 0 LASTPIN (-7425 2250) $PN BU48
J 0
(-7415 2260);
DISPLAY 0.489362 (-7415 2260);
PAINT MONO (-7415 2260);
FORCEPROP 0 LASTPIN (-7425 2200) $PN BU51
J 0
(-7415 2210);
DISPLAY 0.489362 (-7415 2210);
PAINT MONO (-7415 2210);
FORCEPROP 0 LASTPIN (-7425 2150) $PN BU54
J 0
(-7415 2160);
DISPLAY 0.489362 (-7415 2160);
PAINT MONO (-7415 2160);
FORCEPROP 0 LASTPIN (-7425 2100) $PN BU56
J 0
(-7415 2110);
DISPLAY 0.489362 (-7415 2110);
PAINT MONO (-7415 2110);
FORCEPROP 0 LASTPIN (-7425 2050) $PN BU58
J 0
(-7415 2060);
DISPLAY 0.489362 (-7415 2060);
PAINT MONO (-7415 2060);
FORCEPROP 0 LASTPIN (-7425 2000) $PN BU61
J 0
(-7415 2010);
DISPLAY 0.489362 (-7415 2010);
PAINT MONO (-7415 2010);
FORCEPROP 0 LASTPIN (-7425 1950) $PN BU63
J 0
(-7415 1960);
DISPLAY 0.489362 (-7415 1960);
PAINT MONO (-7415 1960);
FORCEPROP 0 LASTPIN (-7425 1900) $PN BU65
J 0
(-7415 1910);
DISPLAY 0.489362 (-7415 1910);
PAINT MONO (-7415 1910);
FORCEPROP 0 LASTPIN (-7425 1850) $PN BU68
J 0
(-7415 1860);
DISPLAY 0.489362 (-7415 1860);
PAINT MONO (-7415 1860);
FORCEPROP 0 LASTPIN (-7425 1800) $PN BU70
J 0
(-7415 1810);
DISPLAY 0.489362 (-7415 1810);
PAINT MONO (-7415 1810);
FORCEPROP 0 LASTPIN (-7425 1750) $PN BU72
J 0
(-7415 1760);
DISPLAY 0.489362 (-7415 1760);
PAINT MONO (-7415 1760);
FORCEPROP 0 LASTPIN (-7425 1700) $PN BU75
J 0
(-7415 1710);
DISPLAY 0.489362 (-7415 1710);
PAINT MONO (-7415 1710);
FORCEPROP 0 LASTPIN (-7425 1650) $PN BV3
J 0
(-7415 1660);
DISPLAY 0.489362 (-7415 1660);
PAINT MONO (-7415 1660);
FORCEPROP 0 LASTPIN (-7425 1600) $PN BV8
J 0
(-7415 1610);
DISPLAY 0.489362 (-7415 1610);
PAINT MONO (-7415 1610);
FORCEPROP 0 LASTPIN (-7425 1550) $PN BV10
J 0
(-7415 1560);
DISPLAY 0.489362 (-7415 1560);
PAINT MONO (-7415 1560);
FORCEPROP 0 LASTPIN (-7425 1500) $PN BV15
J 0
(-7415 1510);
DISPLAY 0.489362 (-7415 1510);
PAINT MONO (-7415 1510);
FORCEPROP 0 LASTPIN (-7425 1450) $PN BV17
J 0
(-7415 1460);
DISPLAY 0.489362 (-7415 1460);
PAINT MONO (-7415 1460);
FORCEPROP 0 LASTPIN (-7425 1400) $PN BV23
J 0
(-7415 1410);
DISPLAY 0.489362 (-7415 1410);
PAINT MONO (-7415 1410);
FORCEPROP 0 LASTPIN (-7425 1350) $PN BV24
J 0
(-7415 1360);
DISPLAY 0.489362 (-7415 1360);
PAINT MONO (-7415 1360);
FORCEPROP 0 LASTPIN (-7425 1300) $PN BV25
J 0
(-7415 1310);
DISPLAY 0.489362 (-7415 1310);
PAINT MONO (-7415 1310);
FORCEPROP 0 LASTPIN (-7425 1250) $PN BV26
J 0
(-7415 1260);
DISPLAY 0.489362 (-7415 1260);
PAINT MONO (-7415 1260);
FORCEPROP 0 LASTPIN (-7425 1200) $PN BV27
J 0
(-7415 1210);
DISPLAY 0.489362 (-7415 1210);
PAINT MONO (-7415 1210);
FORCEPROP 0 LASTPIN (-7425 1150) $PN BV28
J 0
(-7415 1160);
DISPLAY 0.489362 (-7415 1160);
PAINT MONO (-7415 1160);
FORCEPROP 0 LASTPIN (-7425 1100) $PN BV29
J 0
(-7415 1110);
DISPLAY 0.489362 (-7415 1110);
PAINT MONO (-7415 1110);
FORCEPROP 0 LASTPIN (-7425 1050) $PN BV30
J 0
(-7415 1060);
DISPLAY 0.489362 (-7415 1060);
PAINT MONO (-7415 1060);
FORCEPROP 0 LASTPIN (-7425 1000) $PN BV31
J 0
(-7415 1010);
DISPLAY 0.489362 (-7415 1010);
PAINT MONO (-7415 1010);
FORCEPROP 0 LASTPIN (-7425 950) $PN BV32
J 0
(-7415 960);
DISPLAY 0.489362 (-7415 960);
PAINT MONO (-7415 960);
FORCEPROP 0 LASTPIN (-7425 900) $PN BV33
J 0
(-7415 910);
DISPLAY 0.489362 (-7415 910);
PAINT MONO (-7415 910);
FORCEPROP 0 LASTPIN (-7425 850) $PN BV34
J 0
(-7415 860);
DISPLAY 0.489362 (-7415 860);
PAINT MONO (-7415 860);
FORCEPROP 0 LASTPIN (-7425 800) $PN BV37
J 0
(-7415 810);
DISPLAY 0.489362 (-7415 810);
PAINT MONO (-7415 810);
FORCEPROP 0 LASTPIN (-7425 750) $PN BV39
J 0
(-7415 760);
DISPLAY 0.489362 (-7415 760);
PAINT MONO (-7415 760);
FORCEPROP 0 LASTPIN (-7425 700) $PN BV43
J 0
(-7415 710);
DISPLAY 0.489362 (-7415 710);
PAINT MONO (-7415 710);
FORCEPROP 0 LASTPIN (-7425 650) $PN BV44
J 0
(-7415 660);
DISPLAY 0.489362 (-7415 660);
PAINT MONO (-7415 660);
FORCEPROP 0 LASTPIN (-7425 600) $PN BV45
J 0
(-7415 610);
DISPLAY 0.489362 (-7415 610);
PAINT MONO (-7415 610);
FORCEPROP 2 LAST PART_TYPE SMLF
J 0
(-8600 6700);
DISPLAY 1.021277 (-8600 6700);
FORCEPROP 1 LAST MATERIAL IO
J 0
(-8370 6582);
DISPLAY 0.489362 (-8370 6582);
PAINT SKYBLUE (-8370 6582);
FORCEPROP 2 LAST VALUE SOCKET6096_13568-001
J 0
(-8375 6625);
DISPLAY 0.489362 (-8375 6625);
PAINT SKYBLUE (-8375 6625);
FORCEPROP 1 LAST PART_NUMBER DGA^6000030
J 0
(-8375 6725);
DISPLAY 0.489362 (-8375 6725);
PAINT SKYBLUE (-8375 6725);
FORCEPROP 2 LAST CDS_LIB pure_quanta
J 0
(-7975 3500);
DISPLAY INVISIBLE (-7975 3500);
FORCEPROP 1 LAST CDS_LMAN_SYM_OUTLINE -400,3050,400,-3050
J 0
(-7975 3500);
DISPLAY 0.468085 (-7975 3500);
PAINT GREEN (-7975 3500);
DISPLAY INVISIBLE (-7975 3500);
FORCEPROP 1 LAST NEEDS_NO_SIZE TRUE
J 0
(-7975 3500);
DISPLAY 0.723404 (-7975 3500);
PAINT GREEN (-7975 3500);
DISPLAY INVISIBLE (-7975 3500);
FORCEPROP 1 LAST PATH I1
J 0
(-7975 3500);
DISPLAY 0.723404 (-7975 3500);
PAINT GREEN (-7975 3500);
DISPLAY INVISIBLE (-7975 3500);
FORCEADD UNIVERSAL_GND..1
(-6675 475);
FORCEPROP 3 LASTPIN (-6675 525) SIG_NAME GND\g
J 0
(-6665 535);
DISPLAY 0.659574 (-6665 535);
PAINT MONO (-6665 535);
DISPLAY INVISIBLE (-6665 535);
FORCEPROP 2 LAST CDS_LIB pure_quanta_power
J 0
(-6675 475);
DISPLAY INVISIBLE (-6675 475);
FORCEPROP 1 LAST PATH I10
J 0
(-6600 475);
DISPLAY 0.872340 (-6600 475);
PAINT AQUA (-6600 475);
DISPLAY INVISIBLE (-6600 475);
FORCEPROP 1 LAST HDL_POWER GND
J 1
(-6650 400);
DISPLAY 0.872340 (-6650 400);
PAINT GREEN (-6650 400);
DISPLAY INVISIBLE (-6650 400);
FORCEADD UNIVERSAL_GND..1
(-7250 475);
FORCEPROP 3 LASTPIN (-7250 525) SIG_NAME GND\g
J 0
(-7240 535);
DISPLAY 0.659574 (-7240 535);
PAINT MONO (-7240 535);
DISPLAY INVISIBLE (-7240 535);
FORCEPROP 2 LAST CDS_LIB pure_quanta_power
J 0
(-7250 475);
DISPLAY INVISIBLE (-7250 475);
FORCEPROP 1 LAST PATH I11
J 0
(-7175 475);
DISPLAY 0.872340 (-7175 475);
PAINT AQUA (-7175 475);
DISPLAY INVISIBLE (-7175 475);
FORCEPROP 1 LAST HDL_POWER GND
J 1
(-7225 400);
DISPLAY 0.872340 (-7225 400);
PAINT GREEN (-7225 400);
DISPLAY INVISIBLE (-7225 400);
FORCEADD UNIVERSAL_GND..1
(-8700 450);
FORCEPROP 3 LASTPIN (-8700 500) SIG_NAME GND\g
J 0
(-8690 510);
DISPLAY 0.659574 (-8690 510);
PAINT MONO (-8690 510);
DISPLAY INVISIBLE (-8690 510);
FORCEPROP 2 LAST CDS_LIB pure_quanta_power
J 0
(-8700 450);
DISPLAY INVISIBLE (-8700 450);
FORCEPROP 1 LAST PATH I12
J 0
(-8625 450);
DISPLAY 0.872340 (-8625 450);
PAINT AQUA (-8625 450);
DISPLAY INVISIBLE (-8625 450);
FORCEPROP 1 LAST HDL_POWER GND
J 1
(-8675 375);
DISPLAY 0.872340 (-8675 375);
PAINT GREEN (-8675 375);
DISPLAY INVISIBLE (-8675 375);
FORCEADD GENOA_SP5..37
(-5950 3500);
FORCEPROP 1 LAST LOCATION U26
J 0
(-6350 6650);
DISPLAY 0.489362 (-6350 6650);
PAINT SKYBLUE (-6350 6650);
FORCEPROP 0 LAST $SEC 37
J 0
(-6325 6900);
DISPLAY 0.680851 (-6325 6900);
PAINT MONO (-6325 6900);
DISPLAY INVISIBLE (-6325 6900);
FORCEPROP 0 LAST CDS_SEC 37
J 0
(-6325 6900);
DISPLAY 1.021277 (-6325 6900);
DISPLAY INVISIBLE (-6325 6900);
FORCEPROP 0 LASTPIN (-6500 6400) $PN BV46
J 2
(-6510 6410);
DISPLAY 0.489362 (-6510 6410);
PAINT MONO (-6510 6410);
FORCEPROP 0 LASTPIN (-6500 6350) $PN BV47
J 2
(-6510 6360);
DISPLAY 0.489362 (-6510 6360);
PAINT MONO (-6510 6360);
FORCEPROP 0 LASTPIN (-6500 6300) $PN BV48
J 2
(-6510 6310);
DISPLAY 0.489362 (-6510 6310);
PAINT MONO (-6510 6310);
FORCEPROP 0 LASTPIN (-6500 6250) $PN BV49
J 2
(-6510 6260);
DISPLAY 0.489362 (-6510 6260);
PAINT MONO (-6510 6260);
FORCEPROP 0 LASTPIN (-6500 6200) $PN BV50
J 2
(-6510 6210);
DISPLAY 0.489362 (-6510 6210);
PAINT MONO (-6510 6210);
FORCEPROP 0 LASTPIN (-6500 6150) $PN BV51
J 2
(-6510 6160);
DISPLAY 0.489362 (-6510 6160);
PAINT MONO (-6510 6160);
FORCEPROP 0 LASTPIN (-6500 6100) $PN BV52
J 2
(-6510 6110);
DISPLAY 0.489362 (-6510 6110);
PAINT MONO (-6510 6110);
FORCEPROP 0 LASTPIN (-6500 6050) $PN BV53
J 2
(-6510 6060);
DISPLAY 0.489362 (-6510 6060);
PAINT MONO (-6510 6060);
FORCEPROP 0 LASTPIN (-6500 6000) $PN BV59
J 2
(-6510 6010);
DISPLAY 0.489362 (-6510 6010);
PAINT MONO (-6510 6010);
FORCEPROP 0 LASTPIN (-6500 5950) $PN BV61
J 2
(-6510 5960);
DISPLAY 0.489362 (-6510 5960);
PAINT MONO (-6510 5960);
FORCEPROP 0 LASTPIN (-6500 5900) $PN BV66
J 2
(-6510 5910);
DISPLAY 0.489362 (-6510 5910);
PAINT MONO (-6510 5910);
FORCEPROP 0 LASTPIN (-6500 5850) $PN BV68
J 2
(-6510 5860);
DISPLAY 0.489362 (-6510 5860);
PAINT MONO (-6510 5860);
FORCEPROP 0 LASTPIN (-6500 5800) $PN BV73
J 2
(-6510 5810);
DISPLAY 0.489362 (-6510 5810);
PAINT MONO (-6510 5810);
FORCEPROP 0 LASTPIN (-6500 5750) $PN BW1
J 2
(-6510 5760);
DISPLAY 0.489362 (-6510 5760);
PAINT MONO (-6510 5760);
FORCEPROP 0 LASTPIN (-6500 5700) $PN BW4
J 2
(-6510 5710);
DISPLAY 0.489362 (-6510 5710);
PAINT MONO (-6510 5710);
FORCEPROP 0 LASTPIN (-6500 5650) $PN BW6
J 2
(-6510 5660);
DISPLAY 0.489362 (-6510 5660);
PAINT MONO (-6510 5660);
FORCEPROP 0 LASTPIN (-6500 5600) $PN BW8
J 2
(-6510 5610);
DISPLAY 0.489362 (-6510 5610);
PAINT MONO (-6510 5610);
FORCEPROP 0 LASTPIN (-6500 5550) $PN BW11
J 2
(-6510 5560);
DISPLAY 0.489362 (-6510 5560);
PAINT MONO (-6510 5560);
FORCEPROP 0 LASTPIN (-6500 5500) $PN BW13
J 2
(-6510 5510);
DISPLAY 0.489362 (-6510 5510);
PAINT MONO (-6510 5510);
FORCEPROP 0 LASTPIN (-6500 5450) $PN BW15
J 2
(-6510 5460);
DISPLAY 0.489362 (-6510 5460);
PAINT MONO (-6510 5460);
FORCEPROP 0 LASTPIN (-6500 5400) $PN BW18
J 2
(-6510 5410);
DISPLAY 0.489362 (-6510 5410);
PAINT MONO (-6510 5410);
FORCEPROP 0 LASTPIN (-6500 5350) $PN BW20
J 2
(-6510 5360);
DISPLAY 0.489362 (-6510 5360);
PAINT MONO (-6510 5360);
FORCEPROP 0 LASTPIN (-6500 5300) $PN BW22
J 2
(-6510 5310);
DISPLAY 0.489362 (-6510 5310);
PAINT MONO (-6510 5310);
FORCEPROP 0 LASTPIN (-6500 5250) $PN BW28
J 2
(-6510 5260);
DISPLAY 0.489362 (-6510 5260);
PAINT MONO (-6510 5260);
FORCEPROP 0 LASTPIN (-6500 5200) $PN BW31
J 2
(-6510 5210);
DISPLAY 0.489362 (-6510 5210);
PAINT MONO (-6510 5210);
FORCEPROP 0 LASTPIN (-6500 5150) $PN BW34
J 2
(-6510 5160);
DISPLAY 0.489362 (-6510 5160);
PAINT MONO (-6510 5160);
FORCEPROP 0 LASTPIN (-6500 5100) $PN BW42
J 2
(-6510 5110);
DISPLAY 0.489362 (-6510 5110);
PAINT MONO (-6510 5110);
FORCEPROP 0 LASTPIN (-6500 5050) $PN BW45
J 2
(-6510 5060);
DISPLAY 0.489362 (-6510 5060);
PAINT MONO (-6510 5060);
FORCEPROP 0 LASTPIN (-6500 5000) $PN BW48
J 2
(-6510 5010);
DISPLAY 0.489362 (-6510 5010);
PAINT MONO (-6510 5010);
FORCEPROP 0 LASTPIN (-6500 4950) $PN BW51
J 2
(-6510 4960);
DISPLAY 0.489362 (-6510 4960);
PAINT MONO (-6510 4960);
FORCEPROP 0 LASTPIN (-6500 4900) $PN BW54
J 2
(-6510 4910);
DISPLAY 0.489362 (-6510 4910);
PAINT MONO (-6510 4910);
FORCEPROP 0 LASTPIN (-6500 4850) $PN BW56
J 2
(-6510 4860);
DISPLAY 0.489362 (-6510 4860);
PAINT MONO (-6510 4860);
FORCEPROP 0 LASTPIN (-6500 4800) $PN BW58
J 2
(-6510 4810);
DISPLAY 0.489362 (-6510 4810);
PAINT MONO (-6510 4810);
FORCEPROP 0 LASTPIN (-6500 4750) $PN BW61
J 2
(-6510 4760);
DISPLAY 0.489362 (-6510 4760);
PAINT MONO (-6510 4760);
FORCEPROP 0 LASTPIN (-6500 4700) $PN BW63
J 2
(-6510 4710);
DISPLAY 0.489362 (-6510 4710);
PAINT MONO (-6510 4710);
FORCEPROP 0 LASTPIN (-6500 4650) $PN BW65
J 2
(-6510 4660);
DISPLAY 0.489362 (-6510 4660);
PAINT MONO (-6510 4660);
FORCEPROP 0 LASTPIN (-6500 4600) $PN BW68
J 2
(-6510 4610);
DISPLAY 0.489362 (-6510 4610);
PAINT MONO (-6510 4610);
FORCEPROP 0 LASTPIN (-6500 4550) $PN BW70
J 2
(-6510 4560);
DISPLAY 0.489362 (-6510 4560);
PAINT MONO (-6510 4560);
FORCEPROP 0 LASTPIN (-6500 4500) $PN BW72
J 2
(-6510 4510);
DISPLAY 0.489362 (-6510 4510);
PAINT MONO (-6510 4510);
FORCEPROP 0 LASTPIN (-6500 4450) $PN BW75
J 2
(-6510 4460);
DISPLAY 0.489362 (-6510 4460);
PAINT MONO (-6510 4460);
FORCEPROP 0 LASTPIN (-6500 4400) $PN BY3
J 2
(-6510 4410);
DISPLAY 0.489362 (-6510 4410);
PAINT MONO (-6510 4410);
FORCEPROP 0 LASTPIN (-6500 4350) $PN BY5
J 2
(-6510 4360);
DISPLAY 0.489362 (-6510 4360);
PAINT MONO (-6510 4360);
FORCEPROP 0 LASTPIN (-6500 4300) $PN BY8
J 2
(-6510 4310);
DISPLAY 0.489362 (-6510 4310);
PAINT MONO (-6510 4310);
FORCEPROP 0 LASTPIN (-6500 4250) $PN BY10
J 2
(-6510 4260);
DISPLAY 0.489362 (-6510 4260);
PAINT MONO (-6510 4260);
FORCEPROP 0 LASTPIN (-6500 4200) $PN BY12
J 2
(-6510 4210);
DISPLAY 0.489362 (-6510 4210);
PAINT MONO (-6510 4210);
FORCEPROP 0 LASTPIN (-6500 4150) $PN BY15
J 2
(-6510 4160);
DISPLAY 0.489362 (-6510 4160);
PAINT MONO (-6510 4160);
FORCEPROP 0 LASTPIN (-6500 4100) $PN BY17
J 2
(-6510 4110);
DISPLAY 0.489362 (-6510 4110);
PAINT MONO (-6510 4110);
FORCEPROP 0 LASTPIN (-6500 4050) $PN BY19
J 2
(-6510 4060);
DISPLAY 0.489362 (-6510 4060);
PAINT MONO (-6510 4060);
FORCEPROP 0 LASTPIN (-6500 4000) $PN BY22
J 2
(-6510 4010);
DISPLAY 0.489362 (-6510 4010);
PAINT MONO (-6510 4010);
FORCEPROP 0 LASTPIN (-6500 3950) $PN BY25
J 2
(-6510 3960);
DISPLAY 0.489362 (-6510 3960);
PAINT MONO (-6510 3960);
FORCEPROP 0 LASTPIN (-6500 3900) $PN BY28
J 2
(-6510 3910);
DISPLAY 0.489362 (-6510 3910);
PAINT MONO (-6510 3910);
FORCEPROP 0 LASTPIN (-6500 3850) $PN BY31
J 2
(-6510 3860);
DISPLAY 0.489362 (-6510 3860);
PAINT MONO (-6510 3860);
FORCEPROP 0 LASTPIN (-6500 3800) $PN BY34
J 2
(-6510 3810);
DISPLAY 0.489362 (-6510 3810);
PAINT MONO (-6510 3810);
FORCEPROP 0 LASTPIN (-6500 3750) $PN BY37
J 2
(-6510 3760);
DISPLAY 0.489362 (-6510 3760);
PAINT MONO (-6510 3760);
FORCEPROP 0 LASTPIN (-6500 3700) $PN BY39
J 2
(-6510 3710);
DISPLAY 0.489362 (-6510 3710);
PAINT MONO (-6510 3710);
FORCEPROP 0 LASTPIN (-6500 3650) $PN BY42
J 2
(-6510 3660);
DISPLAY 0.489362 (-6510 3660);
PAINT MONO (-6510 3660);
FORCEPROP 0 LASTPIN (-6500 3600) $PN BY45
J 2
(-6510 3610);
DISPLAY 0.489362 (-6510 3610);
PAINT MONO (-6510 3610);
FORCEPROP 0 LASTPIN (-6500 3550) $PN BY48
J 2
(-6510 3560);
DISPLAY 0.489362 (-6510 3560);
PAINT MONO (-6510 3560);
FORCEPROP 0 LASTPIN (-6500 3500) $PN BY51
J 2
(-6510 3510);
DISPLAY 0.489362 (-6510 3510);
PAINT MONO (-6510 3510);
FORCEPROP 0 LASTPIN (-6500 3450) $PN BY54
J 2
(-6510 3460);
DISPLAY 0.489362 (-6510 3460);
PAINT MONO (-6510 3460);
FORCEPROP 0 LASTPIN (-6500 3400) $PN BY57
J 2
(-6510 3410);
DISPLAY 0.489362 (-6510 3410);
PAINT MONO (-6510 3410);
FORCEPROP 0 LASTPIN (-6500 3350) $PN BY59
J 2
(-6510 3360);
DISPLAY 0.489362 (-6510 3360);
PAINT MONO (-6510 3360);
FORCEPROP 0 LASTPIN (-6500 3300) $PN BY61
J 2
(-6510 3310);
DISPLAY 0.489362 (-6510 3310);
PAINT MONO (-6510 3310);
FORCEPROP 0 LASTPIN (-6500 3250) $PN BY64
J 2
(-6510 3260);
DISPLAY 0.489362 (-6510 3260);
PAINT MONO (-6510 3260);
FORCEPROP 0 LASTPIN (-6500 3200) $PN BY66
J 2
(-6510 3210);
DISPLAY 0.489362 (-6510 3210);
PAINT MONO (-6510 3210);
FORCEPROP 0 LASTPIN (-6500 3150) $PN BY68
J 2
(-6510 3160);
DISPLAY 0.489362 (-6510 3160);
PAINT MONO (-6510 3160);
FORCEPROP 0 LASTPIN (-6500 3100) $PN BY71
J 2
(-6510 3110);
DISPLAY 0.489362 (-6510 3110);
PAINT MONO (-6510 3110);
FORCEPROP 0 LASTPIN (-6500 3050) $PN BY73
J 2
(-6510 3060);
DISPLAY 0.489362 (-6510 3060);
PAINT MONO (-6510 3060);
FORCEPROP 0 LASTPIN (-6500 3000) $PN CA1
J 2
(-6510 3010);
DISPLAY 0.489362 (-6510 3010);
PAINT MONO (-6510 3010);
FORCEPROP 0 LASTPIN (-6500 2950) $PN CA6
J 2
(-6510 2960);
DISPLAY 0.489362 (-6510 2960);
PAINT MONO (-6510 2960);
FORCEPROP 0 LASTPIN (-6500 2900) $PN CA8
J 2
(-6510 2910);
DISPLAY 0.489362 (-6510 2910);
PAINT MONO (-6510 2910);
FORCEPROP 0 LASTPIN (-6500 2850) $PN CA13
J 2
(-6510 2860);
DISPLAY 0.489362 (-6510 2860);
PAINT MONO (-6510 2860);
FORCEPROP 0 LASTPIN (-6500 2800) $PN CA15
J 2
(-6510 2810);
DISPLAY 0.489362 (-6510 2810);
PAINT MONO (-6510 2810);
FORCEPROP 0 LASTPIN (-6500 2750) $PN CA20
J 2
(-6510 2760);
DISPLAY 0.489362 (-6510 2760);
PAINT MONO (-6510 2760);
FORCEPROP 0 LASTPIN (-6500 2700) $PN CA22
J 2
(-6510 2710);
DISPLAY 0.489362 (-6510 2710);
PAINT MONO (-6510 2710);
FORCEPROP 0 LASTPIN (-6500 2650) $PN CA25
J 2
(-6510 2660);
DISPLAY 0.489362 (-6510 2660);
PAINT MONO (-6510 2660);
FORCEPROP 0 LASTPIN (-6500 2600) $PN CA28
J 2
(-6510 2610);
DISPLAY 0.489362 (-6510 2610);
PAINT MONO (-6510 2610);
FORCEPROP 0 LASTPIN (-6500 2550) $PN CA31
J 2
(-6510 2560);
DISPLAY 0.489362 (-6510 2560);
PAINT MONO (-6510 2560);
FORCEPROP 0 LASTPIN (-6500 2500) $PN CA34
J 2
(-6510 2510);
DISPLAY 0.489362 (-6510 2510);
PAINT MONO (-6510 2510);
FORCEPROP 0 LASTPIN (-6500 2450) $PN CA35
J 2
(-6510 2460);
DISPLAY 0.489362 (-6510 2460);
PAINT MONO (-6510 2460);
FORCEPROP 0 LASTPIN (-6500 2400) $PN CA36
J 2
(-6510 2410);
DISPLAY 0.489362 (-6510 2410);
PAINT MONO (-6510 2410);
FORCEPROP 0 LASTPIN (-6500 2350) $PN CA40
J 2
(-6510 2360);
DISPLAY 0.489362 (-6510 2360);
PAINT MONO (-6510 2360);
FORCEPROP 0 LASTPIN (-6500 2300) $PN CA41
J 2
(-6510 2310);
DISPLAY 0.489362 (-6510 2310);
PAINT MONO (-6510 2310);
FORCEPROP 0 LASTPIN (-6500 2250) $PN CA42
J 2
(-6510 2260);
DISPLAY 0.489362 (-6510 2260);
PAINT MONO (-6510 2260);
FORCEPROP 0 LASTPIN (-6500 2200) $PN CA45
J 2
(-6510 2210);
DISPLAY 0.489362 (-6510 2210);
PAINT MONO (-6510 2210);
FORCEPROP 0 LASTPIN (-6500 2150) $PN CA48
J 2
(-6510 2160);
DISPLAY 0.489362 (-6510 2160);
PAINT MONO (-6510 2160);
FORCEPROP 0 LASTPIN (-6500 2100) $PN CA51
J 2
(-6510 2110);
DISPLAY 0.489362 (-6510 2110);
PAINT MONO (-6510 2110);
FORCEPROP 0 LASTPIN (-6500 2050) $PN CA54
J 2
(-6510 2060);
DISPLAY 0.489362 (-6510 2060);
PAINT MONO (-6510 2060);
FORCEPROP 0 LASTPIN (-6500 2000) $PN CA56
J 2
(-6510 2010);
DISPLAY 0.489362 (-6510 2010);
PAINT MONO (-6510 2010);
FORCEPROP 0 LASTPIN (-6500 1950) $PN CA61
J 2
(-6510 1960);
DISPLAY 0.489362 (-6510 1960);
PAINT MONO (-6510 1960);
FORCEPROP 0 LASTPIN (-6500 1900) $PN CA63
J 2
(-6510 1910);
DISPLAY 0.489362 (-6510 1910);
PAINT MONO (-6510 1910);
FORCEPROP 0 LASTPIN (-6500 1850) $PN CA68
J 2
(-6510 1860);
DISPLAY 0.489362 (-6510 1860);
PAINT MONO (-6510 1860);
FORCEPROP 0 LASTPIN (-6500 1800) $PN CA70
J 2
(-6510 1810);
DISPLAY 0.489362 (-6510 1810);
PAINT MONO (-6510 1810);
FORCEPROP 0 LASTPIN (-6500 1750) $PN CA75
J 2
(-6510 1760);
DISPLAY 0.489362 (-6510 1760);
PAINT MONO (-6510 1760);
FORCEPROP 0 LASTPIN (-6500 1700) $PN CB3
J 2
(-6510 1710);
DISPLAY 0.489362 (-6510 1710);
PAINT MONO (-6510 1710);
FORCEPROP 0 LASTPIN (-6500 1650) $PN CB5
J 2
(-6510 1660);
DISPLAY 0.489362 (-6510 1660);
PAINT MONO (-6510 1660);
FORCEPROP 0 LASTPIN (-6500 1600) $PN CB8
J 2
(-6510 1610);
DISPLAY 0.489362 (-6510 1610);
PAINT MONO (-6510 1610);
FORCEPROP 0 LASTPIN (-6500 1550) $PN CB10
J 2
(-6510 1560);
DISPLAY 0.489362 (-6510 1560);
PAINT MONO (-6510 1560);
FORCEPROP 0 LASTPIN (-6500 1500) $PN CB12
J 2
(-6510 1510);
DISPLAY 0.489362 (-6510 1510);
PAINT MONO (-6510 1510);
FORCEPROP 0 LASTPIN (-6500 1450) $PN CB15
J 2
(-6510 1460);
DISPLAY 0.489362 (-6510 1460);
PAINT MONO (-6510 1460);
FORCEPROP 0 LASTPIN (-6500 1400) $PN CB17
J 2
(-6510 1410);
DISPLAY 0.489362 (-6510 1410);
PAINT MONO (-6510 1410);
FORCEPROP 0 LASTPIN (-6500 1350) $PN CB19
J 2
(-6510 1360);
DISPLAY 0.489362 (-6510 1360);
PAINT MONO (-6510 1360);
FORCEPROP 0 LASTPIN (-6500 1300) $PN CB23
J 2
(-6510 1310);
DISPLAY 0.489362 (-6510 1310);
PAINT MONO (-6510 1310);
FORCEPROP 0 LASTPIN (-6500 1250) $PN CB24
J 2
(-6510 1260);
DISPLAY 0.489362 (-6510 1260);
PAINT MONO (-6510 1260);
FORCEPROP 0 LASTPIN (-6500 1200) $PN CB25
J 2
(-6510 1210);
DISPLAY 0.489362 (-6510 1210);
PAINT MONO (-6510 1210);
FORCEPROP 0 LASTPIN (-6500 1150) $PN CB26
J 2
(-6510 1160);
DISPLAY 0.489362 (-6510 1160);
PAINT MONO (-6510 1160);
FORCEPROP 0 LASTPIN (-6500 1100) $PN CB27
J 2
(-6510 1110);
DISPLAY 0.489362 (-6510 1110);
PAINT MONO (-6510 1110);
FORCEPROP 0 LASTPIN (-6500 1050) $PN CB28
J 2
(-6510 1060);
DISPLAY 0.489362 (-6510 1060);
PAINT MONO (-6510 1060);
FORCEPROP 0 LASTPIN (-6500 1000) $PN CB29
J 2
(-6510 1010);
DISPLAY 0.489362 (-6510 1010);
PAINT MONO (-6510 1010);
FORCEPROP 0 LASTPIN (-6500 950) $PN CB30
J 2
(-6510 960);
DISPLAY 0.489362 (-6510 960);
PAINT MONO (-6510 960);
FORCEPROP 0 LASTPIN (-6500 900) $PN CB31
J 2
(-6510 910);
DISPLAY 0.489362 (-6510 910);
PAINT MONO (-6510 910);
FORCEPROP 0 LASTPIN (-6500 850) $PN CB32
J 2
(-6510 860);
DISPLAY 0.489362 (-6510 860);
PAINT MONO (-6510 860);
FORCEPROP 0 LASTPIN (-6500 800) $PN CB33
J 2
(-6510 810);
DISPLAY 0.489362 (-6510 810);
PAINT MONO (-6510 810);
FORCEPROP 0 LASTPIN (-6500 750) $PN CB34
J 2
(-6510 760);
DISPLAY 0.489362 (-6510 760);
PAINT MONO (-6510 760);
FORCEPROP 0 LASTPIN (-6500 700) $PN CB37
J 2
(-6510 710);
DISPLAY 0.489362 (-6510 710);
PAINT MONO (-6510 710);
FORCEPROP 0 LASTPIN (-6500 650) $PN CB39
J 2
(-6510 660);
DISPLAY 0.489362 (-6510 660);
PAINT MONO (-6510 660);
FORCEPROP 0 LASTPIN (-6500 600) $PN CB42
J 2
(-6510 610);
DISPLAY 0.489362 (-6510 610);
PAINT MONO (-6510 610);
FORCEPROP 0 LASTPIN (-6500 550) $PN CB43
J 2
(-6510 560);
DISPLAY 0.489362 (-6510 560);
PAINT MONO (-6510 560);
FORCEPROP 0 LASTPIN (-5400 6350) $PN CB45
J 0
(-5390 6360);
DISPLAY 0.489362 (-5390 6360);
PAINT MONO (-5390 6360);
FORCEPROP 0 LASTPIN (-5400 6300) $PN CB46
J 0
(-5390 6310);
DISPLAY 0.489362 (-5390 6310);
PAINT MONO (-5390 6310);
FORCEPROP 0 LASTPIN (-5400 6250) $PN CB47
J 0
(-5390 6260);
DISPLAY 0.489362 (-5390 6260);
PAINT MONO (-5390 6260);
FORCEPROP 0 LASTPIN (-5400 6200) $PN CB48
J 0
(-5390 6210);
DISPLAY 0.489362 (-5390 6210);
PAINT MONO (-5390 6210);
FORCEPROP 0 LASTPIN (-5400 6150) $PN CB49
J 0
(-5390 6160);
DISPLAY 0.489362 (-5390 6160);
PAINT MONO (-5390 6160);
FORCEPROP 0 LASTPIN (-5400 6100) $PN CB50
J 0
(-5390 6110);
DISPLAY 0.489362 (-5390 6110);
PAINT MONO (-5390 6110);
FORCEPROP 0 LASTPIN (-5400 6050) $PN CB51
J 0
(-5390 6060);
DISPLAY 0.489362 (-5390 6060);
PAINT MONO (-5390 6060);
FORCEPROP 0 LASTPIN (-5400 6000) $PN CB52
J 0
(-5390 6010);
DISPLAY 0.489362 (-5390 6010);
PAINT MONO (-5390 6010);
FORCEPROP 0 LASTPIN (-5400 5950) $PN CB53
J 0
(-5390 5960);
DISPLAY 0.489362 (-5390 5960);
PAINT MONO (-5390 5960);
FORCEPROP 0 LASTPIN (-5400 5900) $PN CB57
J 0
(-5390 5910);
DISPLAY 0.489362 (-5390 5910);
PAINT MONO (-5390 5910);
FORCEPROP 0 LASTPIN (-5400 5850) $PN CB59
J 0
(-5390 5860);
DISPLAY 0.489362 (-5390 5860);
PAINT MONO (-5390 5860);
FORCEPROP 0 LASTPIN (-5400 5800) $PN CB61
J 0
(-5390 5810);
DISPLAY 0.489362 (-5390 5810);
PAINT MONO (-5390 5810);
FORCEPROP 0 LASTPIN (-5400 5750) $PN CB64
J 0
(-5390 5760);
DISPLAY 0.489362 (-5390 5760);
PAINT MONO (-5390 5760);
FORCEPROP 0 LASTPIN (-5400 5700) $PN CB66
J 0
(-5390 5710);
DISPLAY 0.489362 (-5390 5710);
PAINT MONO (-5390 5710);
FORCEPROP 0 LASTPIN (-5400 5650) $PN CB68
J 0
(-5390 5660);
DISPLAY 0.489362 (-5390 5660);
PAINT MONO (-5390 5660);
FORCEPROP 0 LASTPIN (-5400 5600) $PN CB71
J 0
(-5390 5610);
DISPLAY 0.489362 (-5390 5610);
PAINT MONO (-5390 5610);
FORCEPROP 0 LASTPIN (-5400 5550) $PN CB73
J 0
(-5390 5560);
DISPLAY 0.489362 (-5390 5560);
PAINT MONO (-5390 5560);
FORCEPROP 0 LASTPIN (-5400 5500) $PN CC1
J 0
(-5390 5510);
DISPLAY 0.489362 (-5390 5510);
PAINT MONO (-5390 5510);
FORCEPROP 0 LASTPIN (-5400 5450) $PN CC4
J 0
(-5390 5460);
DISPLAY 0.489362 (-5390 5460);
PAINT MONO (-5390 5460);
FORCEPROP 0 LASTPIN (-5400 5400) $PN CC6
J 0
(-5390 5410);
DISPLAY 0.489362 (-5390 5410);
PAINT MONO (-5390 5410);
FORCEPROP 0 LASTPIN (-5400 5350) $PN CC8
J 0
(-5390 5360);
DISPLAY 0.489362 (-5390 5360);
PAINT MONO (-5390 5360);
FORCEPROP 0 LASTPIN (-5400 5300) $PN CC11
J 0
(-5390 5310);
DISPLAY 0.489362 (-5390 5310);
PAINT MONO (-5390 5310);
FORCEPROP 0 LASTPIN (-5400 5250) $PN CC13
J 0
(-5390 5260);
DISPLAY 0.489362 (-5390 5260);
PAINT MONO (-5390 5260);
FORCEPROP 0 LASTPIN (-5400 5200) $PN CC15
J 0
(-5390 5210);
DISPLAY 0.489362 (-5390 5210);
PAINT MONO (-5390 5210);
FORCEPROP 0 LASTPIN (-5400 5150) $PN CC18
J 0
(-5390 5160);
DISPLAY 0.489362 (-5390 5160);
PAINT MONO (-5390 5160);
FORCEPROP 0 LASTPIN (-5400 5100) $PN CC20
J 0
(-5390 5110);
DISPLAY 0.489362 (-5390 5110);
PAINT MONO (-5390 5110);
FORCEPROP 0 LASTPIN (-5400 5050) $PN CC25
J 0
(-5390 5060);
DISPLAY 0.489362 (-5390 5060);
PAINT MONO (-5390 5060);
FORCEPROP 0 LASTPIN (-5400 5000) $PN CC28
J 0
(-5390 5010);
DISPLAY 0.489362 (-5390 5010);
PAINT MONO (-5390 5010);
FORCEPROP 0 LASTPIN (-5400 4950) $PN CC31
J 0
(-5390 4960);
DISPLAY 0.489362 (-5390 4960);
PAINT MONO (-5390 4960);
FORCEPROP 0 LASTPIN (-5400 4900) $PN CC34
J 0
(-5390 4910);
DISPLAY 0.489362 (-5390 4910);
PAINT MONO (-5390 4910);
FORCEPROP 0 LASTPIN (-5400 4850) $PN CC42
J 0
(-5390 4860);
DISPLAY 0.489362 (-5390 4860);
PAINT MONO (-5390 4860);
FORCEPROP 0 LASTPIN (-5400 4800) $PN CC45
J 0
(-5390 4810);
DISPLAY 0.489362 (-5390 4810);
PAINT MONO (-5390 4810);
FORCEPROP 0 LASTPIN (-5400 4750) $PN CC48
J 0
(-5390 4760);
DISPLAY 0.489362 (-5390 4760);
PAINT MONO (-5390 4760);
FORCEPROP 0 LASTPIN (-5400 4700) $PN CC51
J 0
(-5390 4710);
DISPLAY 0.489362 (-5390 4710);
PAINT MONO (-5390 4710);
FORCEPROP 0 LASTPIN (-5400 4650) $PN CC54
J 0
(-5390 4660);
DISPLAY 0.489362 (-5390 4660);
PAINT MONO (-5390 4660);
FORCEPROP 0 LASTPIN (-5400 4600) $PN CC56
J 0
(-5390 4610);
DISPLAY 0.489362 (-5390 4610);
PAINT MONO (-5390 4610);
FORCEPROP 0 LASTPIN (-5400 4550) $PN CC58
J 0
(-5390 4560);
DISPLAY 0.489362 (-5390 4560);
PAINT MONO (-5390 4560);
FORCEPROP 0 LASTPIN (-5400 4500) $PN CC61
J 0
(-5390 4510);
DISPLAY 0.489362 (-5390 4510);
PAINT MONO (-5390 4510);
FORCEPROP 0 LASTPIN (-5400 4450) $PN CC63
J 0
(-5390 4460);
DISPLAY 0.489362 (-5390 4460);
PAINT MONO (-5390 4460);
FORCEPROP 0 LASTPIN (-5400 4400) $PN CC65
J 0
(-5390 4410);
DISPLAY 0.489362 (-5390 4410);
PAINT MONO (-5390 4410);
FORCEPROP 0 LASTPIN (-5400 4350) $PN CC68
J 0
(-5390 4360);
DISPLAY 0.489362 (-5390 4360);
PAINT MONO (-5390 4360);
FORCEPROP 0 LASTPIN (-5400 4300) $PN CC70
J 0
(-5390 4310);
DISPLAY 0.489362 (-5390 4310);
PAINT MONO (-5390 4310);
FORCEPROP 0 LASTPIN (-5400 4250) $PN CC72
J 0
(-5390 4260);
DISPLAY 0.489362 (-5390 4260);
PAINT MONO (-5390 4260);
FORCEPROP 0 LASTPIN (-5400 4200) $PN CC75
J 0
(-5390 4210);
DISPLAY 0.489362 (-5390 4210);
PAINT MONO (-5390 4210);
FORCEPROP 0 LASTPIN (-5400 4150) $PN CD3
J 0
(-5390 4160);
DISPLAY 0.489362 (-5390 4160);
PAINT MONO (-5390 4160);
FORCEPROP 0 LASTPIN (-5400 4100) $PN CD8
J 0
(-5390 4110);
DISPLAY 0.489362 (-5390 4110);
PAINT MONO (-5390 4110);
FORCEPROP 0 LASTPIN (-5400 4050) $PN CD10
J 0
(-5390 4060);
DISPLAY 0.489362 (-5390 4060);
PAINT MONO (-5390 4060);
FORCEPROP 0 LASTPIN (-5400 4000) $PN CD15
J 0
(-5390 4010);
DISPLAY 0.489362 (-5390 4010);
PAINT MONO (-5390 4010);
FORCEPROP 0 LASTPIN (-5400 3950) $PN CD17
J 0
(-5390 3960);
DISPLAY 0.489362 (-5390 3960);
PAINT MONO (-5390 3960);
FORCEPROP 0 LASTPIN (-5400 3900) $PN CD22
J 0
(-5390 3910);
DISPLAY 0.489362 (-5390 3910);
PAINT MONO (-5390 3910);
FORCEPROP 0 LASTPIN (-5400 3850) $PN CD25
J 0
(-5390 3860);
DISPLAY 0.489362 (-5390 3860);
PAINT MONO (-5390 3860);
FORCEPROP 0 LASTPIN (-5400 3800) $PN CD28
J 0
(-5390 3810);
DISPLAY 0.489362 (-5390 3810);
PAINT MONO (-5390 3810);
FORCEPROP 0 LASTPIN (-5400 3750) $PN CD31
J 0
(-5390 3760);
DISPLAY 0.489362 (-5390 3760);
PAINT MONO (-5390 3760);
FORCEPROP 0 LASTPIN (-5400 3700) $PN CD34
J 0
(-5390 3710);
DISPLAY 0.489362 (-5390 3710);
PAINT MONO (-5390 3710);
FORCEPROP 0 LASTPIN (-5400 3650) $PN CD37
J 0
(-5390 3660);
DISPLAY 0.489362 (-5390 3660);
PAINT MONO (-5390 3660);
FORCEPROP 0 LASTPIN (-5400 3600) $PN CD39
J 0
(-5390 3610);
DISPLAY 0.489362 (-5390 3610);
PAINT MONO (-5390 3610);
FORCEPROP 0 LASTPIN (-5400 3550) $PN CD42
J 0
(-5390 3560);
DISPLAY 0.489362 (-5390 3560);
PAINT MONO (-5390 3560);
FORCEPROP 0 LASTPIN (-5400 3500) $PN CD45
J 0
(-5390 3510);
DISPLAY 0.489362 (-5390 3510);
PAINT MONO (-5390 3510);
FORCEPROP 0 LASTPIN (-5400 3450) $PN CD48
J 0
(-5390 3460);
DISPLAY 0.489362 (-5390 3460);
PAINT MONO (-5390 3460);
FORCEPROP 0 LASTPIN (-5400 3400) $PN CD51
J 0
(-5390 3410);
DISPLAY 0.489362 (-5390 3410);
PAINT MONO (-5390 3410);
FORCEPROP 0 LASTPIN (-5400 3350) $PN CD54
J 0
(-5390 3360);
DISPLAY 0.489362 (-5390 3360);
PAINT MONO (-5390 3360);
FORCEPROP 0 LASTPIN (-5400 3300) $PN CD59
J 0
(-5390 3310);
DISPLAY 0.489362 (-5390 3310);
PAINT MONO (-5390 3310);
FORCEPROP 0 LASTPIN (-5400 3250) $PN CD61
J 0
(-5390 3260);
DISPLAY 0.489362 (-5390 3260);
PAINT MONO (-5390 3260);
FORCEPROP 0 LASTPIN (-5400 3200) $PN CD66
J 0
(-5390 3210);
DISPLAY 0.489362 (-5390 3210);
PAINT MONO (-5390 3210);
FORCEPROP 0 LASTPIN (-5400 3150) $PN CD68
J 0
(-5390 3160);
DISPLAY 0.489362 (-5390 3160);
PAINT MONO (-5390 3160);
FORCEPROP 0 LASTPIN (-5400 3100) $PN CD73
J 0
(-5390 3110);
DISPLAY 0.489362 (-5390 3110);
PAINT MONO (-5390 3110);
FORCEPROP 0 LASTPIN (-5400 3050) $PN CE1
J 0
(-5390 3060);
DISPLAY 0.489362 (-5390 3060);
PAINT MONO (-5390 3060);
FORCEPROP 0 LASTPIN (-5400 3000) $PN CE4
J 0
(-5390 3010);
DISPLAY 0.489362 (-5390 3010);
PAINT MONO (-5390 3010);
FORCEPROP 0 LASTPIN (-5400 2950) $PN CE6
J 0
(-5390 2960);
DISPLAY 0.489362 (-5390 2960);
PAINT MONO (-5390 2960);
FORCEPROP 0 LASTPIN (-5400 2900) $PN CE8
J 0
(-5390 2910);
DISPLAY 0.489362 (-5390 2910);
PAINT MONO (-5390 2910);
FORCEPROP 0 LASTPIN (-5400 2850) $PN CE11
J 0
(-5390 2860);
DISPLAY 0.489362 (-5390 2860);
PAINT MONO (-5390 2860);
FORCEPROP 0 LASTPIN (-5400 2800) $PN CE13
J 0
(-5390 2810);
DISPLAY 0.489362 (-5390 2810);
PAINT MONO (-5390 2810);
FORCEPROP 0 LASTPIN (-5400 2750) $PN CE15
J 0
(-5390 2760);
DISPLAY 0.489362 (-5390 2760);
PAINT MONO (-5390 2760);
FORCEPROP 0 LASTPIN (-5400 2700) $PN CE18
J 0
(-5390 2710);
DISPLAY 0.489362 (-5390 2710);
PAINT MONO (-5390 2710);
FORCEPROP 0 LASTPIN (-5400 2650) $PN CE20
J 0
(-5390 2660);
DISPLAY 0.489362 (-5390 2660);
PAINT MONO (-5390 2660);
FORCEPROP 0 LASTPIN (-5400 2600) $PN CE22
J 0
(-5390 2610);
DISPLAY 0.489362 (-5390 2610);
PAINT MONO (-5390 2610);
FORCEPROP 0 LASTPIN (-5400 2550) $PN CE25
J 0
(-5390 2560);
DISPLAY 0.489362 (-5390 2560);
PAINT MONO (-5390 2560);
FORCEPROP 0 LASTPIN (-5400 2500) $PN CE28
J 0
(-5390 2510);
DISPLAY 0.489362 (-5390 2510);
PAINT MONO (-5390 2510);
FORCEPROP 0 LASTPIN (-5400 2450) $PN CE31
J 0
(-5390 2460);
DISPLAY 0.489362 (-5390 2460);
PAINT MONO (-5390 2460);
FORCEPROP 0 LASTPIN (-5400 2400) $PN CE34
J 0
(-5390 2410);
DISPLAY 0.489362 (-5390 2410);
PAINT MONO (-5390 2410);
FORCEPROP 0 LASTPIN (-5400 2350) $PN CE35
J 0
(-5390 2360);
DISPLAY 0.489362 (-5390 2360);
PAINT MONO (-5390 2360);
FORCEPROP 0 LASTPIN (-5400 2300) $PN CE36
J 0
(-5390 2310);
DISPLAY 0.489362 (-5390 2310);
PAINT MONO (-5390 2310);
FORCEPROP 0 LASTPIN (-5400 2250) $PN CE40
J 0
(-5390 2260);
DISPLAY 0.489362 (-5390 2260);
PAINT MONO (-5390 2260);
FORCEPROP 0 LASTPIN (-5400 2200) $PN CE41
J 0
(-5390 2210);
DISPLAY 0.489362 (-5390 2210);
PAINT MONO (-5390 2210);
FORCEPROP 0 LASTPIN (-5400 2150) $PN CE42
J 0
(-5390 2160);
DISPLAY 0.489362 (-5390 2160);
PAINT MONO (-5390 2160);
FORCEPROP 0 LASTPIN (-5400 2100) $PN CE45
J 0
(-5390 2110);
DISPLAY 0.489362 (-5390 2110);
PAINT MONO (-5390 2110);
FORCEPROP 0 LASTPIN (-5400 2050) $PN CE48
J 0
(-5390 2060);
DISPLAY 0.489362 (-5390 2060);
PAINT MONO (-5390 2060);
FORCEPROP 0 LASTPIN (-5400 2000) $PN CE51
J 0
(-5390 2010);
DISPLAY 0.489362 (-5390 2010);
PAINT MONO (-5390 2010);
FORCEPROP 0 LASTPIN (-5400 1950) $PN CE54
J 0
(-5390 1960);
DISPLAY 0.489362 (-5390 1960);
PAINT MONO (-5390 1960);
FORCEPROP 0 LASTPIN (-5400 1900) $PN CE56
J 0
(-5390 1910);
DISPLAY 0.489362 (-5390 1910);
PAINT MONO (-5390 1910);
FORCEPROP 0 LASTPIN (-5400 1850) $PN CE58
J 0
(-5390 1860);
DISPLAY 0.489362 (-5390 1860);
PAINT MONO (-5390 1860);
FORCEPROP 0 LASTPIN (-5400 1800) $PN CE61
J 0
(-5390 1810);
DISPLAY 0.489362 (-5390 1810);
PAINT MONO (-5390 1810);
FORCEPROP 0 LASTPIN (-5400 1750) $PN CE63
J 0
(-5390 1760);
DISPLAY 0.489362 (-5390 1760);
PAINT MONO (-5390 1760);
FORCEPROP 0 LASTPIN (-5400 1700) $PN CE65
J 0
(-5390 1710);
DISPLAY 0.489362 (-5390 1710);
PAINT MONO (-5390 1710);
FORCEPROP 0 LASTPIN (-5400 1650) $PN CE68
J 0
(-5390 1660);
DISPLAY 0.489362 (-5390 1660);
PAINT MONO (-5390 1660);
FORCEPROP 0 LASTPIN (-5400 1600) $PN CE70
J 0
(-5390 1610);
DISPLAY 0.489362 (-5390 1610);
PAINT MONO (-5390 1610);
FORCEPROP 0 LASTPIN (-5400 1550) $PN CE72
J 0
(-5390 1560);
DISPLAY 0.489362 (-5390 1560);
PAINT MONO (-5390 1560);
FORCEPROP 0 LASTPIN (-5400 1500) $PN CE75
J 0
(-5390 1510);
DISPLAY 0.489362 (-5390 1510);
PAINT MONO (-5390 1510);
FORCEPROP 0 LASTPIN (-5400 1450) $PN CF3
J 0
(-5390 1460);
DISPLAY 0.489362 (-5390 1460);
PAINT MONO (-5390 1460);
FORCEPROP 0 LASTPIN (-5400 1400) $PN CF5
J 0
(-5390 1410);
DISPLAY 0.489362 (-5390 1410);
PAINT MONO (-5390 1410);
FORCEPROP 0 LASTPIN (-5400 1350) $PN CF8
J 0
(-5390 1360);
DISPLAY 0.489362 (-5390 1360);
PAINT MONO (-5390 1360);
FORCEPROP 0 LASTPIN (-5400 1300) $PN CF10
J 0
(-5390 1310);
DISPLAY 0.489362 (-5390 1310);
PAINT MONO (-5390 1310);
FORCEPROP 0 LASTPIN (-5400 1250) $PN CF12
J 0
(-5390 1260);
DISPLAY 0.489362 (-5390 1260);
PAINT MONO (-5390 1260);
FORCEPROP 0 LASTPIN (-5400 1200) $PN CF15
J 0
(-5390 1210);
DISPLAY 0.489362 (-5390 1210);
PAINT MONO (-5390 1210);
FORCEPROP 0 LASTPIN (-5400 1150) $PN CF17
J 0
(-5390 1160);
DISPLAY 0.489362 (-5390 1160);
PAINT MONO (-5390 1160);
FORCEPROP 0 LASTPIN (-5400 1100) $PN CF19
J 0
(-5390 1110);
DISPLAY 0.489362 (-5390 1110);
PAINT MONO (-5390 1110);
FORCEPROP 0 LASTPIN (-5400 1050) $PN CF23
J 0
(-5390 1060);
DISPLAY 0.489362 (-5390 1060);
PAINT MONO (-5390 1060);
FORCEPROP 0 LASTPIN (-5400 1000) $PN CF24
J 0
(-5390 1010);
DISPLAY 0.489362 (-5390 1010);
PAINT MONO (-5390 1010);
FORCEPROP 0 LASTPIN (-5400 950) $PN CF25
J 0
(-5390 960);
DISPLAY 0.489362 (-5390 960);
PAINT MONO (-5390 960);
FORCEPROP 0 LASTPIN (-5400 900) $PN CF26
J 0
(-5390 910);
DISPLAY 0.489362 (-5390 910);
PAINT MONO (-5390 910);
FORCEPROP 0 LASTPIN (-5400 850) $PN CF27
J 0
(-5390 860);
DISPLAY 0.489362 (-5390 860);
PAINT MONO (-5390 860);
FORCEPROP 0 LASTPIN (-5400 800) $PN CF28
J 0
(-5390 810);
DISPLAY 0.489362 (-5390 810);
PAINT MONO (-5390 810);
FORCEPROP 0 LASTPIN (-5400 750) $PN CF29
J 0
(-5390 760);
DISPLAY 0.489362 (-5390 760);
PAINT MONO (-5390 760);
FORCEPROP 0 LASTPIN (-5400 700) $PN CF30
J 0
(-5390 710);
DISPLAY 0.489362 (-5390 710);
PAINT MONO (-5390 710);
FORCEPROP 0 LASTPIN (-5400 650) $PN CF31
J 0
(-5390 660);
DISPLAY 0.489362 (-5390 660);
PAINT MONO (-5390 660);
FORCEPROP 0 LASTPIN (-5400 600) $PN CF32
J 0
(-5390 610);
DISPLAY 0.489362 (-5390 610);
PAINT MONO (-5390 610);
FORCEPROP 0 LASTPIN (-5400 550) $PN CF33
J 0
(-5390 560);
DISPLAY 0.489362 (-5390 560);
PAINT MONO (-5390 560);
FORCEPROP 2 LAST PART_TYPE SMLF
J 0
(-6550 6700);
DISPLAY 1.021277 (-6550 6700);
FORCEPROP 1 LAST MATERIAL IO
J 0
(-6345 6582);
DISPLAY 0.489362 (-6345 6582);
PAINT SKYBLUE (-6345 6582);
FORCEPROP 2 LAST VALUE SOCKET6096_13568-001
J 0
(-6350 6625);
DISPLAY 0.489362 (-6350 6625);
PAINT SKYBLUE (-6350 6625);
FORCEPROP 1 LAST PART_NUMBER DGA^6000030
J 0
(-6345 6709);
DISPLAY 0.489362 (-6345 6709);
PAINT SKYBLUE (-6345 6709);
FORCEPROP 2 LAST CDS_LIB pure_quanta
J 0
(-5950 3500);
DISPLAY INVISIBLE (-5950 3500);
FORCEPROP 1 LAST CDS_LMAN_SYM_OUTLINE -400,3050,400,-3050
J 0
(-5950 3500);
DISPLAY 0.468085 (-5950 3500);
PAINT GREEN (-5950 3500);
DISPLAY INVISIBLE (-5950 3500);
FORCEPROP 1 LAST NEEDS_NO_SIZE TRUE
J 0
(-5950 3500);
DISPLAY 0.723404 (-5950 3500);
PAINT GREEN (-5950 3500);
DISPLAY INVISIBLE (-5950 3500);
FORCEPROP 1 LAST PATH I2
J 0
(-5950 3500);
DISPLAY 0.723404 (-5950 3500);
PAINT GREEN (-5950 3500);
DISPLAY INVISIBLE (-5950 3500);
FORCEADD GENOA_SP5..38
(-3875 3475);
FORCEPROP 1 LAST LOCATION U26
J 0
(-4275 6650);
DISPLAY 0.489362 (-4275 6650);
PAINT SKYBLUE (-4275 6650);
FORCEPROP 0 LAST $SEC 38
J 0
(-4250 6875);
DISPLAY 0.680851 (-4250 6875);
PAINT MONO (-4250 6875);
DISPLAY INVISIBLE (-4250 6875);
FORCEPROP 0 LAST CDS_SEC 38
J 0
(-4250 6875);
DISPLAY 1.021277 (-4250 6875);
DISPLAY INVISIBLE (-4250 6875);
FORCEPROP 0 LASTPIN (-4425 6325) $PN CF34
J 2
(-4435 6335);
DISPLAY 0.489362 (-4435 6335);
PAINT MONO (-4435 6335);
FORCEPROP 0 LASTPIN (-4425 6275) $PN CF37
J 2
(-4435 6285);
DISPLAY 0.489362 (-4435 6285);
PAINT MONO (-4435 6285);
FORCEPROP 0 LASTPIN (-4425 6225) $PN CF39
J 2
(-4435 6235);
DISPLAY 0.489362 (-4435 6235);
PAINT MONO (-4435 6235);
FORCEPROP 0 LASTPIN (-4425 6175) $PN CF42
J 2
(-4435 6185);
DISPLAY 0.489362 (-4435 6185);
PAINT MONO (-4435 6185);
FORCEPROP 0 LASTPIN (-4425 6125) $PN CF43
J 2
(-4435 6135);
DISPLAY 0.489362 (-4435 6135);
PAINT MONO (-4435 6135);
FORCEPROP 0 LASTPIN (-4425 6075) $PN CF44
J 2
(-4435 6085);
DISPLAY 0.489362 (-4435 6085);
PAINT MONO (-4435 6085);
FORCEPROP 0 LASTPIN (-4425 6025) $PN CF45
J 2
(-4435 6035);
DISPLAY 0.489362 (-4435 6035);
PAINT MONO (-4435 6035);
FORCEPROP 0 LASTPIN (-4425 5975) $PN CF47
J 2
(-4435 5985);
DISPLAY 0.489362 (-4435 5985);
PAINT MONO (-4435 5985);
FORCEPROP 0 LASTPIN (-4425 5925) $PN CF48
J 2
(-4435 5935);
DISPLAY 0.489362 (-4435 5935);
PAINT MONO (-4435 5935);
FORCEPROP 0 LASTPIN (-4425 5875) $PN CF49
J 2
(-4435 5885);
DISPLAY 0.489362 (-4435 5885);
PAINT MONO (-4435 5885);
FORCEPROP 0 LASTPIN (-4425 5825) $PN CF50
J 2
(-4435 5835);
DISPLAY 0.489362 (-4435 5835);
PAINT MONO (-4435 5835);
FORCEPROP 0 LASTPIN (-4425 5775) $PN CF51
J 2
(-4435 5785);
DISPLAY 0.489362 (-4435 5785);
PAINT MONO (-4435 5785);
FORCEPROP 0 LASTPIN (-4425 5725) $PN CF52
J 2
(-4435 5735);
DISPLAY 0.489362 (-4435 5735);
PAINT MONO (-4435 5735);
FORCEPROP 0 LASTPIN (-4425 5675) $PN CF53
J 2
(-4435 5685);
DISPLAY 0.489362 (-4435 5685);
PAINT MONO (-4435 5685);
FORCEPROP 0 LASTPIN (-4425 5625) $PN CF57
J 2
(-4435 5635);
DISPLAY 0.489362 (-4435 5635);
PAINT MONO (-4435 5635);
FORCEPROP 0 LASTPIN (-4425 5575) $PN CF59
J 2
(-4435 5585);
DISPLAY 0.489362 (-4435 5585);
PAINT MONO (-4435 5585);
FORCEPROP 0 LASTPIN (-4425 5525) $PN CF61
J 2
(-4435 5535);
DISPLAY 0.489362 (-4435 5535);
PAINT MONO (-4435 5535);
FORCEPROP 0 LASTPIN (-4425 5475) $PN CF64
J 2
(-4435 5485);
DISPLAY 0.489362 (-4435 5485);
PAINT MONO (-4435 5485);
FORCEPROP 0 LASTPIN (-4425 5425) $PN CF66
J 2
(-4435 5435);
DISPLAY 0.489362 (-4435 5435);
PAINT MONO (-4435 5435);
FORCEPROP 0 LASTPIN (-4425 5375) $PN CF68
J 2
(-4435 5385);
DISPLAY 0.489362 (-4435 5385);
PAINT MONO (-4435 5385);
FORCEPROP 0 LASTPIN (-4425 5325) $PN CF71
J 2
(-4435 5335);
DISPLAY 0.489362 (-4435 5335);
PAINT MONO (-4435 5335);
FORCEPROP 0 LASTPIN (-4425 5275) $PN CF73
J 2
(-4435 5285);
DISPLAY 0.489362 (-4435 5285);
PAINT MONO (-4435 5285);
FORCEPROP 0 LASTPIN (-4425 5225) $PN CG1
J 2
(-4435 5235);
DISPLAY 0.489362 (-4435 5235);
PAINT MONO (-4435 5235);
FORCEPROP 0 LASTPIN (-4425 5175) $PN CG6
J 2
(-4435 5185);
DISPLAY 0.489362 (-4435 5185);
PAINT MONO (-4435 5185);
FORCEPROP 0 LASTPIN (-4425 5125) $PN CG8
J 2
(-4435 5135);
DISPLAY 0.489362 (-4435 5135);
PAINT MONO (-4435 5135);
FORCEPROP 0 LASTPIN (-4425 5075) $PN CG13
J 2
(-4435 5085);
DISPLAY 0.489362 (-4435 5085);
PAINT MONO (-4435 5085);
FORCEPROP 0 LASTPIN (-4425 5025) $PN CG15
J 2
(-4435 5035);
DISPLAY 0.489362 (-4435 5035);
PAINT MONO (-4435 5035);
FORCEPROP 0 LASTPIN (-4425 4975) $PN CG20
J 2
(-4435 4985);
DISPLAY 0.489362 (-4435 4985);
PAINT MONO (-4435 4985);
FORCEPROP 0 LASTPIN (-4425 4925) $PN CG22
J 2
(-4435 4935);
DISPLAY 0.489362 (-4435 4935);
PAINT MONO (-4435 4935);
FORCEPROP 0 LASTPIN (-4425 4875) $PN CG25
J 2
(-4435 4885);
DISPLAY 0.489362 (-4435 4885);
PAINT MONO (-4435 4885);
FORCEPROP 0 LASTPIN (-4425 4825) $PN CG28
J 2
(-4435 4835);
DISPLAY 0.489362 (-4435 4835);
PAINT MONO (-4435 4835);
FORCEPROP 0 LASTPIN (-4425 4775) $PN CG31
J 2
(-4435 4785);
DISPLAY 0.489362 (-4435 4785);
PAINT MONO (-4435 4785);
FORCEPROP 0 LASTPIN (-4425 4725) $PN CG34
J 2
(-4435 4735);
DISPLAY 0.489362 (-4435 4735);
PAINT MONO (-4435 4735);
FORCEPROP 0 LASTPIN (-4425 4675) $PN CG45
J 2
(-4435 4685);
DISPLAY 0.489362 (-4435 4685);
PAINT MONO (-4435 4685);
FORCEPROP 0 LASTPIN (-4425 4625) $PN CG48
J 2
(-4435 4635);
DISPLAY 0.489362 (-4435 4635);
PAINT MONO (-4435 4635);
FORCEPROP 0 LASTPIN (-4425 4575) $PN CG51
J 2
(-4435 4585);
DISPLAY 0.489362 (-4435 4585);
PAINT MONO (-4435 4585);
FORCEPROP 0 LASTPIN (-4425 4525) $PN CG54
J 2
(-4435 4535);
DISPLAY 0.489362 (-4435 4535);
PAINT MONO (-4435 4535);
FORCEPROP 0 LASTPIN (-4425 4475) $PN CG56
J 2
(-4435 4485);
DISPLAY 0.489362 (-4435 4485);
PAINT MONO (-4435 4485);
FORCEPROP 0 LASTPIN (-4425 4425) $PN CG61
J 2
(-4435 4435);
DISPLAY 0.489362 (-4435 4435);
PAINT MONO (-4435 4435);
FORCEPROP 0 LASTPIN (-4425 4375) $PN CG63
J 2
(-4435 4385);
DISPLAY 0.489362 (-4435 4385);
PAINT MONO (-4435 4385);
FORCEPROP 0 LASTPIN (-4425 4325) $PN CG68
J 2
(-4435 4335);
DISPLAY 0.489362 (-4435 4335);
PAINT MONO (-4435 4335);
FORCEPROP 0 LASTPIN (-4425 4275) $PN CG70
J 2
(-4435 4285);
DISPLAY 0.489362 (-4435 4285);
PAINT MONO (-4435 4285);
FORCEPROP 0 LASTPIN (-4425 4225) $PN CG75
J 2
(-4435 4235);
DISPLAY 0.489362 (-4435 4235);
PAINT MONO (-4435 4235);
FORCEPROP 0 LASTPIN (-4425 4175) $PN CH3
J 2
(-4435 4185);
DISPLAY 0.489362 (-4435 4185);
PAINT MONO (-4435 4185);
FORCEPROP 0 LASTPIN (-4425 4125) $PN CH5
J 2
(-4435 4135);
DISPLAY 0.489362 (-4435 4135);
PAINT MONO (-4435 4135);
FORCEPROP 0 LASTPIN (-4425 4075) $PN CH8
J 2
(-4435 4085);
DISPLAY 0.489362 (-4435 4085);
PAINT MONO (-4435 4085);
FORCEPROP 0 LASTPIN (-4425 4025) $PN CH10
J 2
(-4435 4035);
DISPLAY 0.489362 (-4435 4035);
PAINT MONO (-4435 4035);
FORCEPROP 0 LASTPIN (-4425 3975) $PN CH12
J 2
(-4435 3985);
DISPLAY 0.489362 (-4435 3985);
PAINT MONO (-4435 3985);
FORCEPROP 0 LASTPIN (-4425 3925) $PN CH15
J 2
(-4435 3935);
DISPLAY 0.489362 (-4435 3935);
PAINT MONO (-4435 3935);
FORCEPROP 0 LASTPIN (-4425 3875) $PN CH17
J 2
(-4435 3885);
DISPLAY 0.489362 (-4435 3885);
PAINT MONO (-4435 3885);
FORCEPROP 0 LASTPIN (-4425 3825) $PN CH19
J 2
(-4435 3835);
DISPLAY 0.489362 (-4435 3835);
PAINT MONO (-4435 3835);
FORCEPROP 0 LASTPIN (-4425 3775) $PN CH22
J 2
(-4435 3785);
DISPLAY 0.489362 (-4435 3785);
PAINT MONO (-4435 3785);
FORCEPROP 0 LASTPIN (-4425 3725) $PN CH25
J 2
(-4435 3735);
DISPLAY 0.489362 (-4435 3735);
PAINT MONO (-4435 3735);
FORCEPROP 0 LASTPIN (-4425 3675) $PN CH28
J 2
(-4435 3685);
DISPLAY 0.489362 (-4435 3685);
PAINT MONO (-4435 3685);
FORCEPROP 0 LASTPIN (-4425 3625) $PN CH31
J 2
(-4435 3635);
DISPLAY 0.489362 (-4435 3635);
PAINT MONO (-4435 3635);
FORCEPROP 0 LASTPIN (-4425 3575) $PN CH34
J 2
(-4435 3585);
DISPLAY 0.489362 (-4435 3585);
PAINT MONO (-4435 3585);
FORCEPROP 0 LASTPIN (-4425 3525) $PN CH37
J 2
(-4435 3535);
DISPLAY 0.489362 (-4435 3535);
PAINT MONO (-4435 3535);
FORCEPROP 0 LASTPIN (-4425 3475) $PN CH39
J 2
(-4435 3485);
DISPLAY 0.489362 (-4435 3485);
PAINT MONO (-4435 3485);
FORCEPROP 0 LASTPIN (-4425 3425) $PN CH42
J 2
(-4435 3435);
DISPLAY 0.489362 (-4435 3435);
PAINT MONO (-4435 3435);
FORCEPROP 0 LASTPIN (-4425 3375) $PN CH45
J 2
(-4435 3385);
DISPLAY 0.489362 (-4435 3385);
PAINT MONO (-4435 3385);
FORCEPROP 0 LASTPIN (-4425 3325) $PN CH48
J 2
(-4435 3335);
DISPLAY 0.489362 (-4435 3335);
PAINT MONO (-4435 3335);
FORCEPROP 0 LASTPIN (-4425 3275) $PN CH51
J 2
(-4435 3285);
DISPLAY 0.489362 (-4435 3285);
PAINT MONO (-4435 3285);
FORCEPROP 0 LASTPIN (-4425 3225) $PN CH54
J 2
(-4435 3235);
DISPLAY 0.489362 (-4435 3235);
PAINT MONO (-4435 3235);
FORCEPROP 0 LASTPIN (-4425 3175) $PN CH57
J 2
(-4435 3185);
DISPLAY 0.489362 (-4435 3185);
PAINT MONO (-4435 3185);
FORCEPROP 0 LASTPIN (-4425 3125) $PN CH59
J 2
(-4435 3135);
DISPLAY 0.489362 (-4435 3135);
PAINT MONO (-4435 3135);
FORCEPROP 0 LASTPIN (-4425 3075) $PN CH61
J 2
(-4435 3085);
DISPLAY 0.489362 (-4435 3085);
PAINT MONO (-4435 3085);
FORCEPROP 0 LASTPIN (-4425 3025) $PN CH64
J 2
(-4435 3035);
DISPLAY 0.489362 (-4435 3035);
PAINT MONO (-4435 3035);
FORCEPROP 0 LASTPIN (-4425 2975) $PN CH66
J 2
(-4435 2985);
DISPLAY 0.489362 (-4435 2985);
PAINT MONO (-4435 2985);
FORCEPROP 0 LASTPIN (-4425 2925) $PN CH68
J 2
(-4435 2935);
DISPLAY 0.489362 (-4435 2935);
PAINT MONO (-4435 2935);
FORCEPROP 0 LASTPIN (-4425 2875) $PN CH71
J 2
(-4435 2885);
DISPLAY 0.489362 (-4435 2885);
PAINT MONO (-4435 2885);
FORCEPROP 0 LASTPIN (-4425 2825) $PN CH73
J 2
(-4435 2835);
DISPLAY 0.489362 (-4435 2835);
PAINT MONO (-4435 2835);
FORCEPROP 0 LASTPIN (-4425 2775) $PN CJ1
J 2
(-4435 2785);
DISPLAY 0.489362 (-4435 2785);
PAINT MONO (-4435 2785);
FORCEPROP 0 LASTPIN (-4425 2725) $PN CJ4
J 2
(-4435 2735);
DISPLAY 0.489362 (-4435 2735);
PAINT MONO (-4435 2735);
FORCEPROP 0 LASTPIN (-4425 2675) $PN CJ6
J 2
(-4435 2685);
DISPLAY 0.489362 (-4435 2685);
PAINT MONO (-4435 2685);
FORCEPROP 0 LASTPIN (-4425 2625) $PN CJ8
J 2
(-4435 2635);
DISPLAY 0.489362 (-4435 2635);
PAINT MONO (-4435 2635);
FORCEPROP 0 LASTPIN (-4425 2575) $PN CJ11
J 2
(-4435 2585);
DISPLAY 0.489362 (-4435 2585);
PAINT MONO (-4435 2585);
FORCEPROP 0 LASTPIN (-4425 2525) $PN CJ13
J 2
(-4435 2535);
DISPLAY 0.489362 (-4435 2535);
PAINT MONO (-4435 2535);
FORCEPROP 0 LASTPIN (-4425 2475) $PN CJ15
J 2
(-4435 2485);
DISPLAY 0.489362 (-4435 2485);
PAINT MONO (-4435 2485);
FORCEPROP 0 LASTPIN (-4425 2425) $PN CJ18
J 2
(-4435 2435);
DISPLAY 0.489362 (-4435 2435);
PAINT MONO (-4435 2435);
FORCEPROP 0 LASTPIN (-4425 2375) $PN CJ20
J 2
(-4435 2385);
DISPLAY 0.489362 (-4435 2385);
PAINT MONO (-4435 2385);
FORCEPROP 0 LASTPIN (-4425 2325) $PN CJ23
J 2
(-4435 2335);
DISPLAY 0.489362 (-4435 2335);
PAINT MONO (-4435 2335);
FORCEPROP 0 LASTPIN (-4425 2275) $PN CJ31
J 2
(-4435 2285);
DISPLAY 0.489362 (-4435 2285);
PAINT MONO (-4435 2285);
FORCEPROP 0 LASTPIN (-4425 2225) $PN CJ34
J 2
(-4435 2235);
DISPLAY 0.489362 (-4435 2235);
PAINT MONO (-4435 2235);
FORCEPROP 0 LASTPIN (-4425 2175) $PN CJ35
J 2
(-4435 2185);
DISPLAY 0.489362 (-4435 2185);
PAINT MONO (-4435 2185);
FORCEPROP 0 LASTPIN (-4425 2125) $PN CJ36
J 2
(-4435 2135);
DISPLAY 0.489362 (-4435 2135);
PAINT MONO (-4435 2135);
FORCEPROP 0 LASTPIN (-4425 2075) $PN CJ40
J 2
(-4435 2085);
DISPLAY 0.489362 (-4435 2085);
PAINT MONO (-4435 2085);
FORCEPROP 0 LASTPIN (-4425 2025) $PN CJ41
J 2
(-4435 2035);
DISPLAY 0.489362 (-4435 2035);
PAINT MONO (-4435 2035);
FORCEPROP 0 LASTPIN (-4425 1975) $PN CJ42
J 2
(-4435 1985);
DISPLAY 0.489362 (-4435 1985);
PAINT MONO (-4435 1985);
FORCEPROP 0 LASTPIN (-4425 1925) $PN CJ45
J 2
(-4435 1935);
DISPLAY 0.489362 (-4435 1935);
PAINT MONO (-4435 1935);
FORCEPROP 0 LASTPIN (-4425 1875) $PN CJ56
J 2
(-4435 1885);
DISPLAY 0.489362 (-4435 1885);
PAINT MONO (-4435 1885);
FORCEPROP 0 LASTPIN (-4425 1825) $PN CJ58
J 2
(-4435 1835);
DISPLAY 0.489362 (-4435 1835);
PAINT MONO (-4435 1835);
FORCEPROP 0 LASTPIN (-4425 1775) $PN CJ61
J 2
(-4435 1785);
DISPLAY 0.489362 (-4435 1785);
PAINT MONO (-4435 1785);
FORCEPROP 0 LASTPIN (-4425 1725) $PN CJ63
J 2
(-4435 1735);
DISPLAY 0.489362 (-4435 1735);
PAINT MONO (-4435 1735);
FORCEPROP 0 LASTPIN (-4425 1675) $PN CJ65
J 2
(-4435 1685);
DISPLAY 0.489362 (-4435 1685);
PAINT MONO (-4435 1685);
FORCEPROP 0 LASTPIN (-4425 1625) $PN CJ68
J 2
(-4435 1635);
DISPLAY 0.489362 (-4435 1635);
PAINT MONO (-4435 1635);
FORCEPROP 0 LASTPIN (-4425 1575) $PN CJ70
J 2
(-4435 1585);
DISPLAY 0.489362 (-4435 1585);
PAINT MONO (-4435 1585);
FORCEPROP 0 LASTPIN (-4425 1525) $PN CJ72
J 2
(-4435 1535);
DISPLAY 0.489362 (-4435 1535);
PAINT MONO (-4435 1535);
FORCEPROP 0 LASTPIN (-4425 1475) $PN CJ75
J 2
(-4435 1485);
DISPLAY 0.489362 (-4435 1485);
PAINT MONO (-4435 1485);
FORCEPROP 0 LASTPIN (-4425 1425) $PN CK3
J 2
(-4435 1435);
DISPLAY 0.489362 (-4435 1435);
PAINT MONO (-4435 1435);
FORCEPROP 0 LASTPIN (-4425 1375) $PN CK8
J 2
(-4435 1385);
DISPLAY 0.489362 (-4435 1385);
PAINT MONO (-4435 1385);
FORCEPROP 0 LASTPIN (-4425 1325) $PN CK15
J 2
(-4435 1335);
DISPLAY 0.489362 (-4435 1335);
PAINT MONO (-4435 1335);
FORCEPROP 0 LASTPIN (-4425 1275) $PN CK17
J 2
(-4435 1285);
DISPLAY 0.489362 (-4435 1285);
PAINT MONO (-4435 1285);
FORCEPROP 0 LASTPIN (-4425 1225) $PN CK22
J 2
(-4435 1235);
DISPLAY 0.489362 (-4435 1235);
PAINT MONO (-4435 1235);
FORCEPROP 0 LASTPIN (-4425 1175) $PN CK23
J 2
(-4435 1185);
DISPLAY 0.489362 (-4435 1185);
PAINT MONO (-4435 1185);
FORCEPROP 0 LASTPIN (-4425 1125) $PN CK24
J 2
(-4435 1135);
DISPLAY 0.489362 (-4435 1135);
PAINT MONO (-4435 1135);
FORCEPROP 0 LASTPIN (-4425 1075) $PN CK25
J 2
(-4435 1085);
DISPLAY 0.489362 (-4435 1085);
PAINT MONO (-4435 1085);
FORCEPROP 0 LASTPIN (-4425 1025) $PN CK26
J 2
(-4435 1035);
DISPLAY 0.489362 (-4435 1035);
PAINT MONO (-4435 1035);
FORCEPROP 0 LASTPIN (-4425 975) $PN CK27
J 2
(-4435 985);
DISPLAY 0.489362 (-4435 985);
PAINT MONO (-4435 985);
FORCEPROP 0 LASTPIN (-4425 925) $PN CK28
J 2
(-4435 935);
DISPLAY 0.489362 (-4435 935);
PAINT MONO (-4435 935);
FORCEPROP 0 LASTPIN (-4425 875) $PN CK32
J 2
(-4435 885);
DISPLAY 0.489362 (-4435 885);
PAINT MONO (-4435 885);
FORCEPROP 0 LASTPIN (-4425 825) $PN CK33
J 2
(-4435 835);
DISPLAY 0.489362 (-4435 835);
PAINT MONO (-4435 835);
FORCEPROP 0 LASTPIN (-4425 775) $PN CK34
J 2
(-4435 785);
DISPLAY 0.489362 (-4435 785);
PAINT MONO (-4435 785);
FORCEPROP 0 LASTPIN (-4425 725) $PN CK37
J 2
(-4435 735);
DISPLAY 0.489362 (-4435 735);
PAINT MONO (-4435 735);
FORCEPROP 0 LASTPIN (-4425 675) $PN CK39
J 2
(-4435 685);
DISPLAY 0.489362 (-4435 685);
PAINT MONO (-4435 685);
FORCEPROP 0 LASTPIN (-4425 625) $PN CK42
J 2
(-4435 635);
DISPLAY 0.489362 (-4435 635);
PAINT MONO (-4435 635);
FORCEPROP 0 LASTPIN (-3325 6425) $PN CK43
J 0
(-3315 6435);
DISPLAY 0.489362 (-3315 6435);
PAINT MONO (-3315 6435);
FORCEPROP 0 LASTPIN (-3325 6375) $PN CK44
J 0
(-3315 6385);
DISPLAY 0.489362 (-3315 6385);
PAINT MONO (-3315 6385);
FORCEPROP 0 LASTPIN (-3325 6325) $PN CK45
J 0
(-3315 6335);
DISPLAY 0.489362 (-3315 6335);
PAINT MONO (-3315 6335);
FORCEPROP 0 LASTPIN (-3325 6275) $PN CK48
J 0
(-3315 6285);
DISPLAY 0.489362 (-3315 6285);
PAINT MONO (-3315 6285);
FORCEPROP 0 LASTPIN (-3325 6225) $PN CK49
J 0
(-3315 6235);
DISPLAY 0.489362 (-3315 6235);
PAINT MONO (-3315 6235);
FORCEPROP 0 LASTPIN (-3325 6175) $PN CK50
J 0
(-3315 6185);
DISPLAY 0.489362 (-3315 6185);
PAINT MONO (-3315 6185);
FORCEPROP 0 LASTPIN (-3325 6125) $PN CK51
J 0
(-3315 6135);
DISPLAY 0.489362 (-3315 6135);
PAINT MONO (-3315 6135);
FORCEPROP 0 LASTPIN (-3325 6075) $PN CK52
J 0
(-3315 6085);
DISPLAY 0.489362 (-3315 6085);
PAINT MONO (-3315 6085);
FORCEPROP 0 LASTPIN (-3325 6025) $PN CK53
J 0
(-3315 6035);
DISPLAY 0.489362 (-3315 6035);
PAINT MONO (-3315 6035);
FORCEPROP 0 LASTPIN (-3325 5975) $PN CK54
J 0
(-3315 5985);
DISPLAY 0.489362 (-3315 5985);
PAINT MONO (-3315 5985);
FORCEPROP 0 LASTPIN (-3325 5925) $PN CK59
J 0
(-3315 5935);
DISPLAY 0.489362 (-3315 5935);
PAINT MONO (-3315 5935);
FORCEPROP 0 LASTPIN (-3325 5875) $PN CK61
J 0
(-3315 5885);
DISPLAY 0.489362 (-3315 5885);
PAINT MONO (-3315 5885);
FORCEPROP 0 LASTPIN (-3325 5825) $PN CK66
J 0
(-3315 5835);
DISPLAY 0.489362 (-3315 5835);
PAINT MONO (-3315 5835);
FORCEPROP 0 LASTPIN (-3325 5775) $PN CK68
J 0
(-3315 5785);
DISPLAY 0.489362 (-3315 5785);
PAINT MONO (-3315 5785);
FORCEPROP 0 LASTPIN (-3325 5725) $PN CK73
J 0
(-3315 5735);
DISPLAY 0.489362 (-3315 5735);
PAINT MONO (-3315 5735);
FORCEPROP 0 LASTPIN (-3325 5675) $PN CL1
J 0
(-3315 5685);
DISPLAY 0.489362 (-3315 5685);
PAINT MONO (-3315 5685);
FORCEPROP 0 LASTPIN (-3325 5625) $PN CL4
J 0
(-3315 5635);
DISPLAY 0.489362 (-3315 5635);
PAINT MONO (-3315 5635);
FORCEPROP 0 LASTPIN (-3325 5575) $PN CL6
J 0
(-3315 5585);
DISPLAY 0.489362 (-3315 5585);
PAINT MONO (-3315 5585);
FORCEPROP 0 LASTPIN (-3325 5525) $PN CL8
J 0
(-3315 5535);
DISPLAY 0.489362 (-3315 5535);
PAINT MONO (-3315 5535);
FORCEPROP 0 LASTPIN (-3325 5475) $PN CL11
J 0
(-3315 5485);
DISPLAY 0.489362 (-3315 5485);
PAINT MONO (-3315 5485);
FORCEPROP 0 LASTPIN (-3325 5425) $PN CL13
J 0
(-3315 5435);
DISPLAY 0.489362 (-3315 5435);
PAINT MONO (-3315 5435);
FORCEPROP 0 LASTPIN (-3325 5375) $PN CL15
J 0
(-3315 5385);
DISPLAY 0.489362 (-3315 5385);
PAINT MONO (-3315 5385);
FORCEPROP 0 LASTPIN (-3325 5325) $PN CL18
J 0
(-3315 5335);
DISPLAY 0.489362 (-3315 5335);
PAINT MONO (-3315 5335);
FORCEPROP 0 LASTPIN (-3325 5275) $PN CL20
J 0
(-3315 5285);
DISPLAY 0.489362 (-3315 5285);
PAINT MONO (-3315 5285);
FORCEPROP 0 LASTPIN (-3325 5225) $PN CL22
J 0
(-3315 5235);
DISPLAY 0.489362 (-3315 5235);
PAINT MONO (-3315 5235);
FORCEPROP 0 LASTPIN (-3325 5175) $PN CL25
J 0
(-3315 5185);
DISPLAY 0.489362 (-3315 5185);
PAINT MONO (-3315 5185);
FORCEPROP 0 LASTPIN (-3325 5125) $PN CL28
J 0
(-3315 5135);
DISPLAY 0.489362 (-3315 5135);
PAINT MONO (-3315 5135);
FORCEPROP 0 LASTPIN (-3325 5075) $PN CL31
J 0
(-3315 5085);
DISPLAY 0.489362 (-3315 5085);
PAINT MONO (-3315 5085);
FORCEPROP 0 LASTPIN (-3325 5025) $PN CL34
J 0
(-3315 5035);
DISPLAY 0.489362 (-3315 5035);
PAINT MONO (-3315 5035);
FORCEPROP 0 LASTPIN (-3325 4975) $PN CL35
J 0
(-3315 4985);
DISPLAY 0.489362 (-3315 4985);
PAINT MONO (-3315 4985);
FORCEPROP 0 LASTPIN (-3325 4925) $PN CL36
J 0
(-3315 4935);
DISPLAY 0.489362 (-3315 4935);
PAINT MONO (-3315 4935);
FORCEPROP 0 LASTPIN (-3325 4875) $PN CL40
J 0
(-3315 4885);
DISPLAY 0.489362 (-3315 4885);
PAINT MONO (-3315 4885);
FORCEPROP 0 LASTPIN (-3325 4825) $PN CL41
J 0
(-3315 4835);
DISPLAY 0.489362 (-3315 4835);
PAINT MONO (-3315 4835);
FORCEPROP 0 LASTPIN (-3325 4775) $PN CL42
J 0
(-3315 4785);
DISPLAY 0.489362 (-3315 4785);
PAINT MONO (-3315 4785);
FORCEPROP 0 LASTPIN (-3325 4725) $PN CL45
J 0
(-3315 4735);
DISPLAY 0.489362 (-3315 4735);
PAINT MONO (-3315 4735);
FORCEPROP 0 LASTPIN (-3325 4675) $PN CL48
J 0
(-3315 4685);
DISPLAY 0.489362 (-3315 4685);
PAINT MONO (-3315 4685);
FORCEPROP 0 LASTPIN (-3325 4625) $PN CL51
J 0
(-3315 4635);
DISPLAY 0.489362 (-3315 4635);
PAINT MONO (-3315 4635);
FORCEPROP 0 LASTPIN (-3325 4575) $PN CL54
J 0
(-3315 4585);
DISPLAY 0.489362 (-3315 4585);
PAINT MONO (-3315 4585);
FORCEPROP 0 LASTPIN (-3325 4525) $PN CL56
J 0
(-3315 4535);
DISPLAY 0.489362 (-3315 4535);
PAINT MONO (-3315 4535);
FORCEPROP 0 LASTPIN (-3325 4475) $PN CL58
J 0
(-3315 4485);
DISPLAY 0.489362 (-3315 4485);
PAINT MONO (-3315 4485);
FORCEPROP 0 LASTPIN (-3325 4425) $PN CL61
J 0
(-3315 4435);
DISPLAY 0.489362 (-3315 4435);
PAINT MONO (-3315 4435);
FORCEPROP 0 LASTPIN (-3325 4375) $PN CL63
J 0
(-3315 4385);
DISPLAY 0.489362 (-3315 4385);
PAINT MONO (-3315 4385);
FORCEPROP 0 LASTPIN (-3325 4325) $PN CL65
J 0
(-3315 4335);
DISPLAY 0.489362 (-3315 4335);
PAINT MONO (-3315 4335);
FORCEPROP 0 LASTPIN (-3325 4275) $PN CL68
J 0
(-3315 4285);
DISPLAY 0.489362 (-3315 4285);
PAINT MONO (-3315 4285);
FORCEPROP 0 LASTPIN (-3325 4225) $PN CL70
J 0
(-3315 4235);
DISPLAY 0.489362 (-3315 4235);
PAINT MONO (-3315 4235);
FORCEPROP 0 LASTPIN (-3325 4175) $PN CL72
J 0
(-3315 4185);
DISPLAY 0.489362 (-3315 4185);
PAINT MONO (-3315 4185);
FORCEPROP 0 LASTPIN (-3325 4125) $PN CL75
J 0
(-3315 4135);
DISPLAY 0.489362 (-3315 4135);
PAINT MONO (-3315 4135);
FORCEPROP 0 LASTPIN (-3325 4075) $PN CM3
J 0
(-3315 4085);
DISPLAY 0.489362 (-3315 4085);
PAINT MONO (-3315 4085);
FORCEPROP 0 LASTPIN (-3325 4025) $PN CM5
J 0
(-3315 4035);
DISPLAY 0.489362 (-3315 4035);
PAINT MONO (-3315 4035);
FORCEPROP 0 LASTPIN (-3325 3975) $PN CM8
J 0
(-3315 3985);
DISPLAY 0.489362 (-3315 3985);
PAINT MONO (-3315 3985);
FORCEPROP 0 LASTPIN (-3325 3925) $PN CM10
J 0
(-3315 3935);
DISPLAY 0.489362 (-3315 3935);
PAINT MONO (-3315 3935);
FORCEPROP 0 LASTPIN (-3325 3875) $PN CM12
J 0
(-3315 3885);
DISPLAY 0.489362 (-3315 3885);
PAINT MONO (-3315 3885);
FORCEPROP 0 LASTPIN (-3325 3825) $PN CM15
J 0
(-3315 3835);
DISPLAY 0.489362 (-3315 3835);
PAINT MONO (-3315 3835);
FORCEPROP 0 LASTPIN (-3325 3775) $PN CM17
J 0
(-3315 3785);
DISPLAY 0.489362 (-3315 3785);
PAINT MONO (-3315 3785);
FORCEPROP 0 LASTPIN (-3325 3725) $PN CM19
J 0
(-3315 3735);
DISPLAY 0.489362 (-3315 3735);
PAINT MONO (-3315 3735);
FORCEPROP 0 LASTPIN (-3325 3675) $PN CM23
J 0
(-3315 3685);
DISPLAY 0.489362 (-3315 3685);
PAINT MONO (-3315 3685);
FORCEPROP 0 LASTPIN (-3325 3625) $PN CM24
J 0
(-3315 3635);
DISPLAY 0.489362 (-3315 3635);
PAINT MONO (-3315 3635);
FORCEPROP 0 LASTPIN (-3325 3575) $PN CM25
J 0
(-3315 3585);
DISPLAY 0.489362 (-3315 3585);
PAINT MONO (-3315 3585);
FORCEPROP 0 LASTPIN (-3325 3525) $PN CM26
J 0
(-3315 3535);
DISPLAY 0.489362 (-3315 3535);
PAINT MONO (-3315 3535);
FORCEPROP 0 LASTPIN (-3325 3475) $PN CM27
J 0
(-3315 3485);
DISPLAY 0.489362 (-3315 3485);
PAINT MONO (-3315 3485);
FORCEPROP 0 LASTPIN (-3325 3425) $PN CM28
J 0
(-3315 3435);
DISPLAY 0.489362 (-3315 3435);
PAINT MONO (-3315 3435);
FORCEPROP 0 LASTPIN (-3325 3375) $PN CM29
J 0
(-3315 3385);
DISPLAY 0.489362 (-3315 3385);
PAINT MONO (-3315 3385);
FORCEPROP 0 LASTPIN (-3325 3325) $PN CM30
J 0
(-3315 3335);
DISPLAY 0.489362 (-3315 3335);
PAINT MONO (-3315 3335);
FORCEPROP 0 LASTPIN (-3325 3275) $PN CM31
J 0
(-3315 3285);
DISPLAY 0.489362 (-3315 3285);
PAINT MONO (-3315 3285);
FORCEPROP 0 LASTPIN (-3325 3225) $PN CM32
J 0
(-3315 3235);
DISPLAY 0.489362 (-3315 3235);
PAINT MONO (-3315 3235);
FORCEPROP 0 LASTPIN (-3325 3175) $PN CM33
J 0
(-3315 3185);
DISPLAY 0.489362 (-3315 3185);
PAINT MONO (-3315 3185);
FORCEPROP 0 LASTPIN (-3325 3125) $PN CM34
J 0
(-3315 3135);
DISPLAY 0.489362 (-3315 3135);
PAINT MONO (-3315 3135);
FORCEPROP 0 LASTPIN (-3325 3075) $PN CM37
J 0
(-3315 3085);
DISPLAY 0.489362 (-3315 3085);
PAINT MONO (-3315 3085);
FORCEPROP 0 LASTPIN (-3325 3025) $PN CM39
J 0
(-3315 3035);
DISPLAY 0.489362 (-3315 3035);
PAINT MONO (-3315 3035);
FORCEPROP 0 LASTPIN (-3325 2975) $PN CM42
J 0
(-3315 2985);
DISPLAY 0.489362 (-3315 2985);
PAINT MONO (-3315 2985);
FORCEPROP 0 LASTPIN (-3325 2925) $PN CM43
J 0
(-3315 2935);
DISPLAY 0.489362 (-3315 2935);
PAINT MONO (-3315 2935);
FORCEPROP 0 LASTPIN (-3325 2875) $PN CM44
J 0
(-3315 2885);
DISPLAY 0.489362 (-3315 2885);
PAINT MONO (-3315 2885);
FORCEPROP 0 LASTPIN (-3325 2825) $PN CM45
J 0
(-3315 2835);
DISPLAY 0.489362 (-3315 2835);
PAINT MONO (-3315 2835);
FORCEPROP 0 LASTPIN (-3325 2775) $PN CM46
J 0
(-3315 2785);
DISPLAY 0.489362 (-3315 2785);
PAINT MONO (-3315 2785);
FORCEPROP 0 LASTPIN (-3325 2725) $PN CM47
J 0
(-3315 2735);
DISPLAY 0.489362 (-3315 2735);
PAINT MONO (-3315 2735);
FORCEPROP 0 LASTPIN (-3325 2675) $PN CM48
J 0
(-3315 2685);
DISPLAY 0.489362 (-3315 2685);
PAINT MONO (-3315 2685);
FORCEPROP 0 LASTPIN (-3325 2625) $PN CM49
J 0
(-3315 2635);
DISPLAY 0.489362 (-3315 2635);
PAINT MONO (-3315 2635);
FORCEPROP 0 LASTPIN (-3325 2575) $PN CM51
J 0
(-3315 2585);
DISPLAY 0.489362 (-3315 2585);
PAINT MONO (-3315 2585);
FORCEPROP 0 LASTPIN (-3325 2525) $PN CM52
J 0
(-3315 2535);
DISPLAY 0.489362 (-3315 2535);
PAINT MONO (-3315 2535);
FORCEPROP 0 LASTPIN (-3325 2475) $PN CM53
J 0
(-3315 2485);
DISPLAY 0.489362 (-3315 2485);
PAINT MONO (-3315 2485);
FORCEPROP 0 LASTPIN (-3325 2425) $PN CM57
J 0
(-3315 2435);
DISPLAY 0.489362 (-3315 2435);
PAINT MONO (-3315 2435);
FORCEPROP 0 LASTPIN (-3325 2375) $PN CM59
J 0
(-3315 2385);
DISPLAY 0.489362 (-3315 2385);
PAINT MONO (-3315 2385);
FORCEPROP 0 LASTPIN (-3325 2325) $PN CM61
J 0
(-3315 2335);
DISPLAY 0.489362 (-3315 2335);
PAINT MONO (-3315 2335);
FORCEPROP 0 LASTPIN (-3325 2275) $PN CM64
J 0
(-3315 2285);
DISPLAY 0.489362 (-3315 2285);
PAINT MONO (-3315 2285);
FORCEPROP 0 LASTPIN (-3325 2225) $PN CM66
J 0
(-3315 2235);
DISPLAY 0.489362 (-3315 2235);
PAINT MONO (-3315 2235);
FORCEPROP 0 LASTPIN (-3325 2175) $PN CM68
J 0
(-3315 2185);
DISPLAY 0.489362 (-3315 2185);
PAINT MONO (-3315 2185);
FORCEPROP 0 LASTPIN (-3325 2125) $PN CM71
J 0
(-3315 2135);
DISPLAY 0.489362 (-3315 2135);
PAINT MONO (-3315 2135);
FORCEPROP 0 LASTPIN (-3325 2075) $PN CM73
J 0
(-3315 2085);
DISPLAY 0.489362 (-3315 2085);
PAINT MONO (-3315 2085);
FORCEPROP 0 LASTPIN (-3325 2025) $PN CN1
J 0
(-3315 2035);
DISPLAY 0.489362 (-3315 2035);
PAINT MONO (-3315 2035);
FORCEPROP 0 LASTPIN (-3325 1975) $PN CN6
J 0
(-3315 1985);
DISPLAY 0.489362 (-3315 1985);
PAINT MONO (-3315 1985);
FORCEPROP 0 LASTPIN (-3325 1925) $PN CN8
J 0
(-3315 1935);
DISPLAY 0.489362 (-3315 1935);
PAINT MONO (-3315 1935);
FORCEPROP 0 LASTPIN (-3325 1875) $PN CN13
J 0
(-3315 1885);
DISPLAY 0.489362 (-3315 1885);
PAINT MONO (-3315 1885);
FORCEPROP 0 LASTPIN (-3325 1825) $PN CN15
J 0
(-3315 1835);
DISPLAY 0.489362 (-3315 1835);
PAINT MONO (-3315 1835);
FORCEPROP 0 LASTPIN (-3325 1775) $PN CN20
J 0
(-3315 1785);
DISPLAY 0.489362 (-3315 1785);
PAINT MONO (-3315 1785);
FORCEPROP 0 LASTPIN (-3325 1725) $PN CN22
J 0
(-3315 1735);
DISPLAY 0.489362 (-3315 1735);
PAINT MONO (-3315 1735);
FORCEPROP 0 LASTPIN (-3325 1675) $PN CN25
J 0
(-3315 1685);
DISPLAY 0.489362 (-3315 1685);
PAINT MONO (-3315 1685);
FORCEPROP 0 LASTPIN (-3325 1625) $PN CN28
J 0
(-3315 1635);
DISPLAY 0.489362 (-3315 1635);
PAINT MONO (-3315 1635);
FORCEPROP 0 LASTPIN (-3325 1575) $PN CN31
J 0
(-3315 1585);
DISPLAY 0.489362 (-3315 1585);
PAINT MONO (-3315 1585);
FORCEPROP 0 LASTPIN (-3325 1525) $PN CN34
J 0
(-3315 1535);
DISPLAY 0.489362 (-3315 1535);
PAINT MONO (-3315 1535);
FORCEPROP 0 LASTPIN (-3325 1475) $PN CN42
J 0
(-3315 1485);
DISPLAY 0.489362 (-3315 1485);
PAINT MONO (-3315 1485);
FORCEPROP 0 LASTPIN (-3325 1425) $PN CN45
J 0
(-3315 1435);
DISPLAY 0.489362 (-3315 1435);
PAINT MONO (-3315 1435);
FORCEPROP 0 LASTPIN (-3325 1375) $PN CN48
J 0
(-3315 1385);
DISPLAY 0.489362 (-3315 1385);
PAINT MONO (-3315 1385);
FORCEPROP 0 LASTPIN (-3325 1325) $PN CN51
J 0
(-3315 1335);
DISPLAY 0.489362 (-3315 1335);
PAINT MONO (-3315 1335);
FORCEPROP 0 LASTPIN (-3325 1275) $PN CN56
J 0
(-3315 1285);
DISPLAY 0.489362 (-3315 1285);
PAINT MONO (-3315 1285);
FORCEPROP 0 LASTPIN (-3325 1225) $PN CN61
J 0
(-3315 1235);
DISPLAY 0.489362 (-3315 1235);
PAINT MONO (-3315 1235);
FORCEPROP 0 LASTPIN (-3325 1175) $PN CN63
J 0
(-3315 1185);
DISPLAY 0.489362 (-3315 1185);
PAINT MONO (-3315 1185);
FORCEPROP 0 LASTPIN (-3325 1125) $PN CN68
J 0
(-3315 1135);
DISPLAY 0.489362 (-3315 1135);
PAINT MONO (-3315 1135);
FORCEPROP 0 LASTPIN (-3325 1075) $PN CN70
J 0
(-3315 1085);
DISPLAY 0.489362 (-3315 1085);
PAINT MONO (-3315 1085);
FORCEPROP 0 LASTPIN (-3325 1025) $PN CN75
J 0
(-3315 1035);
DISPLAY 0.489362 (-3315 1035);
PAINT MONO (-3315 1035);
FORCEPROP 0 LASTPIN (-3325 975) $PN CP3
J 0
(-3315 985);
DISPLAY 0.489362 (-3315 985);
PAINT MONO (-3315 985);
FORCEPROP 0 LASTPIN (-3325 925) $PN CP5
J 0
(-3315 935);
DISPLAY 0.489362 (-3315 935);
PAINT MONO (-3315 935);
FORCEPROP 0 LASTPIN (-3325 875) $PN CP8
J 0
(-3315 885);
DISPLAY 0.489362 (-3315 885);
PAINT MONO (-3315 885);
FORCEPROP 0 LASTPIN (-3325 825) $PN CP10
J 0
(-3315 835);
DISPLAY 0.489362 (-3315 835);
PAINT MONO (-3315 835);
FORCEPROP 0 LASTPIN (-3325 775) $PN CP12
J 0
(-3315 785);
DISPLAY 0.489362 (-3315 785);
PAINT MONO (-3315 785);
FORCEPROP 0 LASTPIN (-3325 725) $PN CP15
J 0
(-3315 735);
DISPLAY 0.489362 (-3315 735);
PAINT MONO (-3315 735);
FORCEPROP 0 LASTPIN (-3325 675) $PN CP17
J 0
(-3315 685);
DISPLAY 0.489362 (-3315 685);
PAINT MONO (-3315 685);
FORCEPROP 0 LASTPIN (-3325 625) $PN CP19
J 0
(-3315 635);
DISPLAY 0.489362 (-3315 635);
PAINT MONO (-3315 635);
FORCEPROP 2 LAST PART_TYPE SMLF
J 0
(-4500 6675);
DISPLAY 1.021277 (-4500 6675);
FORCEPROP 1 LAST MATERIAL IO
J 0
(-4270 6557);
DISPLAY 0.489362 (-4270 6557);
PAINT SKYBLUE (-4270 6557);
FORCEPROP 2 LAST VALUE SOCKET6096_13568-001
J 0
(-4275 6600);
DISPLAY 0.489362 (-4275 6600);
PAINT SKYBLUE (-4275 6600);
FORCEPROP 1 LAST PART_NUMBER DGA^6000030
J 0
(-4275 6700);
DISPLAY 0.489362 (-4275 6700);
PAINT SKYBLUE (-4275 6700);
FORCEPROP 2 LAST CDS_LIB pure_quanta
J 0
(-3875 3475);
DISPLAY INVISIBLE (-3875 3475);
FORCEPROP 1 LAST CDS_LMAN_SYM_OUTLINE -400,3050,400,-3050
J 0
(-3875 3475);
DISPLAY 0.468085 (-3875 3475);
PAINT GREEN (-3875 3475);
DISPLAY INVISIBLE (-3875 3475);
FORCEPROP 1 LAST NEEDS_NO_SIZE TRUE
J 0
(-3875 3475);
DISPLAY 0.723404 (-3875 3475);
PAINT GREEN (-3875 3475);
DISPLAY INVISIBLE (-3875 3475);
FORCEPROP 1 LAST PATH I3
J 0
(-3875 3475);
DISPLAY 0.723404 (-3875 3475);
PAINT GREEN (-3875 3475);
DISPLAY INVISIBLE (-3875 3475);
FORCEADD GENOA_SP5..39
(-1800 3500);
FORCEPROP 1 LAST LOCATION U26
J 0
(-2200 6650);
DISPLAY 0.489362 (-2200 6650);
PAINT SKYBLUE (-2200 6650);
FORCEPROP 0 LAST $SEC 39
J 0
(-2175 6900);
DISPLAY 0.680851 (-2175 6900);
PAINT MONO (-2175 6900);
DISPLAY INVISIBLE (-2175 6900);
FORCEPROP 0 LAST CDS_SEC 39
J 0
(-2175 6900);
DISPLAY 1.021277 (-2175 6900);
DISPLAY INVISIBLE (-2175 6900);
FORCEPROP 0 LASTPIN (-1250 550) $PN CP22
J 0
(-1240 560);
DISPLAY 0.489362 (-1240 560);
PAINT MONO (-1240 560);
FORCEPROP 0 LASTPIN (-1250 600) $PN CP25
J 0
(-1240 610);
DISPLAY 0.489362 (-1240 610);
PAINT MONO (-1240 610);
FORCEPROP 0 LASTPIN (-1250 650) $PN CP28
J 0
(-1240 660);
DISPLAY 0.489362 (-1240 660);
PAINT MONO (-1240 660);
FORCEPROP 0 LASTPIN (-1250 700) $PN CP31
J 0
(-1240 710);
DISPLAY 0.489362 (-1240 710);
PAINT MONO (-1240 710);
FORCEPROP 0 LASTPIN (-1250 750) $PN CP34
J 0
(-1240 760);
DISPLAY 0.489362 (-1240 760);
PAINT MONO (-1240 760);
FORCEPROP 0 LASTPIN (-1250 800) $PN CP37
J 0
(-1240 810);
DISPLAY 0.489362 (-1240 810);
PAINT MONO (-1240 810);
FORCEPROP 0 LASTPIN (-1250 850) $PN CP39
J 0
(-1240 860);
DISPLAY 0.489362 (-1240 860);
PAINT MONO (-1240 860);
FORCEPROP 0 LASTPIN (-1250 900) $PN CP42
J 0
(-1240 910);
DISPLAY 0.489362 (-1240 910);
PAINT MONO (-1240 910);
FORCEPROP 0 LASTPIN (-1250 950) $PN CP45
J 0
(-1240 960);
DISPLAY 0.489362 (-1240 960);
PAINT MONO (-1240 960);
FORCEPROP 0 LASTPIN (-1250 1000) $PN CP48
J 0
(-1240 1010);
DISPLAY 0.489362 (-1240 1010);
PAINT MONO (-1240 1010);
FORCEPROP 0 LASTPIN (-1250 1050) $PN CP51
J 0
(-1240 1060);
DISPLAY 0.489362 (-1240 1060);
PAINT MONO (-1240 1060);
FORCEPROP 0 LASTPIN (-1250 1100) $PN CP54
J 0
(-1240 1110);
DISPLAY 0.489362 (-1240 1110);
PAINT MONO (-1240 1110);
FORCEPROP 0 LASTPIN (-1250 1150) $PN CP57
J 0
(-1240 1160);
DISPLAY 0.489362 (-1240 1160);
PAINT MONO (-1240 1160);
FORCEPROP 0 LASTPIN (-1250 1200) $PN CP59
J 0
(-1240 1210);
DISPLAY 0.489362 (-1240 1210);
PAINT MONO (-1240 1210);
FORCEPROP 0 LASTPIN (-1250 1250) $PN CP61
J 0
(-1240 1260);
DISPLAY 0.489362 (-1240 1260);
PAINT MONO (-1240 1260);
FORCEPROP 0 LASTPIN (-1250 1300) $PN CP64
J 0
(-1240 1310);
DISPLAY 0.489362 (-1240 1310);
PAINT MONO (-1240 1310);
FORCEPROP 0 LASTPIN (-1250 1350) $PN CP66
J 0
(-1240 1360);
DISPLAY 0.489362 (-1240 1360);
PAINT MONO (-1240 1360);
FORCEPROP 0 LASTPIN (-1250 1400) $PN CP68
J 0
(-1240 1410);
DISPLAY 0.489362 (-1240 1410);
PAINT MONO (-1240 1410);
FORCEPROP 0 LASTPIN (-1250 1450) $PN CP71
J 0
(-1240 1460);
DISPLAY 0.489362 (-1240 1460);
PAINT MONO (-1240 1460);
FORCEPROP 0 LASTPIN (-1250 1500) $PN CP73
J 0
(-1240 1510);
DISPLAY 0.489362 (-1240 1510);
PAINT MONO (-1240 1510);
FORCEPROP 0 LASTPIN (-1250 1550) $PN CR1
J 0
(-1240 1560);
DISPLAY 0.489362 (-1240 1560);
PAINT MONO (-1240 1560);
FORCEPROP 0 LASTPIN (-1250 1600) $PN CR4
J 0
(-1240 1610);
DISPLAY 0.489362 (-1240 1610);
PAINT MONO (-1240 1610);
FORCEPROP 0 LASTPIN (-1250 1650) $PN CR6
J 0
(-1240 1660);
DISPLAY 0.489362 (-1240 1660);
PAINT MONO (-1240 1660);
FORCEPROP 0 LASTPIN (-1250 1700) $PN CR8
J 0
(-1240 1710);
DISPLAY 0.489362 (-1240 1710);
PAINT MONO (-1240 1710);
FORCEPROP 0 LASTPIN (-1250 1750) $PN CR11
J 0
(-1240 1760);
DISPLAY 0.489362 (-1240 1760);
PAINT MONO (-1240 1760);
FORCEPROP 0 LASTPIN (-1250 1800) $PN CR13
J 0
(-1240 1810);
DISPLAY 0.489362 (-1240 1810);
PAINT MONO (-1240 1810);
FORCEPROP 0 LASTPIN (-1250 1850) $PN CR15
J 0
(-1240 1860);
DISPLAY 0.489362 (-1240 1860);
PAINT MONO (-1240 1860);
FORCEPROP 0 LASTPIN (-1250 1900) $PN CR18
J 0
(-1240 1910);
DISPLAY 0.489362 (-1240 1910);
PAINT MONO (-1240 1910);
FORCEPROP 0 LASTPIN (-1250 1950) $PN CR20
J 0
(-1240 1960);
DISPLAY 0.489362 (-1240 1960);
PAINT MONO (-1240 1960);
FORCEPROP 0 LASTPIN (-1250 2000) $PN CR22
J 0
(-1240 2010);
DISPLAY 0.489362 (-1240 2010);
PAINT MONO (-1240 2010);
FORCEPROP 0 LASTPIN (-1250 2050) $PN CR25
J 0
(-1240 2060);
DISPLAY 0.489362 (-1240 2060);
PAINT MONO (-1240 2060);
FORCEPROP 0 LASTPIN (-1250 2100) $PN CR28
J 0
(-1240 2110);
DISPLAY 0.489362 (-1240 2110);
PAINT MONO (-1240 2110);
FORCEPROP 0 LASTPIN (-1250 2150) $PN CR31
J 0
(-1240 2160);
DISPLAY 0.489362 (-1240 2160);
PAINT MONO (-1240 2160);
FORCEPROP 0 LASTPIN (-1250 2200) $PN CR34
J 0
(-1240 2210);
DISPLAY 0.489362 (-1240 2210);
PAINT MONO (-1240 2210);
FORCEPROP 0 LASTPIN (-1250 2250) $PN CR35
J 0
(-1240 2260);
DISPLAY 0.489362 (-1240 2260);
PAINT MONO (-1240 2260);
FORCEPROP 0 LASTPIN (-1250 2300) $PN CR36
J 0
(-1240 2310);
DISPLAY 0.489362 (-1240 2310);
PAINT MONO (-1240 2310);
FORCEPROP 0 LASTPIN (-1250 2350) $PN CR40
J 0
(-1240 2360);
DISPLAY 0.489362 (-1240 2360);
PAINT MONO (-1240 2360);
FORCEPROP 0 LASTPIN (-1250 2400) $PN CR41
J 0
(-1240 2410);
DISPLAY 0.489362 (-1240 2410);
PAINT MONO (-1240 2410);
FORCEPROP 0 LASTPIN (-1250 2450) $PN CR42
J 0
(-1240 2460);
DISPLAY 0.489362 (-1240 2460);
PAINT MONO (-1240 2460);
FORCEPROP 0 LASTPIN (-1250 2500) $PN CR45
J 0
(-1240 2510);
DISPLAY 0.489362 (-1240 2510);
PAINT MONO (-1240 2510);
FORCEPROP 0 LASTPIN (-1250 2550) $PN CR48
J 0
(-1240 2560);
DISPLAY 0.489362 (-1240 2560);
PAINT MONO (-1240 2560);
FORCEPROP 0 LASTPIN (-1250 2600) $PN CR51
J 0
(-1240 2610);
DISPLAY 0.489362 (-1240 2610);
PAINT MONO (-1240 2610);
FORCEPROP 0 LASTPIN (-1250 2650) $PN CR54
J 0
(-1240 2660);
DISPLAY 0.489362 (-1240 2660);
PAINT MONO (-1240 2660);
FORCEPROP 0 LASTPIN (-1250 2700) $PN CR56
J 0
(-1240 2710);
DISPLAY 0.489362 (-1240 2710);
PAINT MONO (-1240 2710);
FORCEPROP 0 LASTPIN (-1250 2750) $PN CR58
J 0
(-1240 2760);
DISPLAY 0.489362 (-1240 2760);
PAINT MONO (-1240 2760);
FORCEPROP 0 LASTPIN (-1250 2800) $PN CR61
J 0
(-1240 2810);
DISPLAY 0.489362 (-1240 2810);
PAINT MONO (-1240 2810);
FORCEPROP 0 LASTPIN (-1250 2850) $PN CR63
J 0
(-1240 2860);
DISPLAY 0.489362 (-1240 2860);
PAINT MONO (-1240 2860);
FORCEPROP 0 LASTPIN (-1250 2900) $PN CR65
J 0
(-1240 2910);
DISPLAY 0.489362 (-1240 2910);
PAINT MONO (-1240 2910);
FORCEPROP 0 LASTPIN (-1250 2950) $PN CR68
J 0
(-1240 2960);
DISPLAY 0.489362 (-1240 2960);
PAINT MONO (-1240 2960);
FORCEPROP 0 LASTPIN (-1250 3000) $PN CR70
J 0
(-1240 3010);
DISPLAY 0.489362 (-1240 3010);
PAINT MONO (-1240 3010);
FORCEPROP 0 LASTPIN (-1250 3050) $PN CR72
J 0
(-1240 3060);
DISPLAY 0.489362 (-1240 3060);
PAINT MONO (-1240 3060);
FORCEPROP 0 LASTPIN (-1250 3100) $PN CR75
J 0
(-1240 3110);
DISPLAY 0.489362 (-1240 3110);
PAINT MONO (-1240 3110);
FORCEPROP 0 LASTPIN (-1250 3150) $PN CT3
J 0
(-1240 3160);
DISPLAY 0.489362 (-1240 3160);
PAINT MONO (-1240 3160);
FORCEPROP 0 LASTPIN (-1250 3200) $PN CT8
J 0
(-1240 3210);
DISPLAY 0.489362 (-1240 3210);
PAINT MONO (-1240 3210);
FORCEPROP 0 LASTPIN (-1250 3250) $PN CT10
J 0
(-1240 3260);
DISPLAY 0.489362 (-1240 3260);
PAINT MONO (-1240 3260);
FORCEPROP 0 LASTPIN (-1250 3300) $PN CT15
J 0
(-1240 3310);
DISPLAY 0.489362 (-1240 3310);
PAINT MONO (-1240 3310);
FORCEPROP 0 LASTPIN (-1250 3350) $PN CT17
J 0
(-1240 3360);
DISPLAY 0.489362 (-1240 3360);
PAINT MONO (-1240 3360);
FORCEPROP 0 LASTPIN (-1250 3400) $PN CT23
J 0
(-1240 3410);
DISPLAY 0.489362 (-1240 3410);
PAINT MONO (-1240 3410);
FORCEPROP 0 LASTPIN (-1250 3450) $PN CT24
J 0
(-1240 3460);
DISPLAY 0.489362 (-1240 3460);
PAINT MONO (-1240 3460);
FORCEPROP 0 LASTPIN (-1250 3500) $PN CT25
J 0
(-1240 3510);
DISPLAY 0.489362 (-1240 3510);
PAINT MONO (-1240 3510);
FORCEPROP 0 LASTPIN (-1250 3550) $PN CT26
J 0
(-1240 3560);
DISPLAY 0.489362 (-1240 3560);
PAINT MONO (-1240 3560);
FORCEPROP 0 LASTPIN (-1250 3600) $PN CT27
J 0
(-1240 3610);
DISPLAY 0.489362 (-1240 3610);
PAINT MONO (-1240 3610);
FORCEPROP 0 LASTPIN (-1250 3650) $PN CT28
J 0
(-1240 3660);
DISPLAY 0.489362 (-1240 3660);
PAINT MONO (-1240 3660);
FORCEPROP 0 LASTPIN (-1250 3700) $PN CT29
J 0
(-1240 3710);
DISPLAY 0.489362 (-1240 3710);
PAINT MONO (-1240 3710);
FORCEPROP 0 LASTPIN (-1250 3750) $PN CT30
J 0
(-1240 3760);
DISPLAY 0.489362 (-1240 3760);
PAINT MONO (-1240 3760);
FORCEPROP 0 LASTPIN (-1250 3800) $PN CT31
J 0
(-1240 3810);
DISPLAY 0.489362 (-1240 3810);
PAINT MONO (-1240 3810);
FORCEPROP 0 LASTPIN (-1250 3850) $PN CT32
J 0
(-1240 3860);
DISPLAY 0.489362 (-1240 3860);
PAINT MONO (-1240 3860);
FORCEPROP 0 LASTPIN (-1250 3900) $PN CT33
J 0
(-1240 3910);
DISPLAY 0.489362 (-1240 3910);
PAINT MONO (-1240 3910);
FORCEPROP 0 LASTPIN (-1250 3950) $PN CT34
J 0
(-1240 3960);
DISPLAY 0.489362 (-1240 3960);
PAINT MONO (-1240 3960);
FORCEPROP 0 LASTPIN (-1250 4000) $PN CT37
J 0
(-1240 4010);
DISPLAY 0.489362 (-1240 4010);
PAINT MONO (-1240 4010);
FORCEPROP 0 LASTPIN (-1250 4050) $PN CT39
J 0
(-1240 4060);
DISPLAY 0.489362 (-1240 4060);
PAINT MONO (-1240 4060);
FORCEPROP 0 LASTPIN (-1250 4100) $PN CT42
J 0
(-1240 4110);
DISPLAY 0.489362 (-1240 4110);
PAINT MONO (-1240 4110);
FORCEPROP 0 LASTPIN (-1250 4150) $PN CT43
J 0
(-1240 4160);
DISPLAY 0.489362 (-1240 4160);
PAINT MONO (-1240 4160);
FORCEPROP 0 LASTPIN (-1250 4200) $PN CT44
J 0
(-1240 4210);
DISPLAY 0.489362 (-1240 4210);
PAINT MONO (-1240 4210);
FORCEPROP 0 LASTPIN (-1250 4250) $PN CT45
J 0
(-1240 4260);
DISPLAY 0.489362 (-1240 4260);
PAINT MONO (-1240 4260);
FORCEPROP 0 LASTPIN (-1250 4300) $PN CT46
J 0
(-1240 4310);
DISPLAY 0.489362 (-1240 4310);
PAINT MONO (-1240 4310);
FORCEPROP 0 LASTPIN (-1250 4350) $PN CT47
J 0
(-1240 4360);
DISPLAY 0.489362 (-1240 4360);
PAINT MONO (-1240 4360);
FORCEPROP 0 LASTPIN (-1250 4400) $PN CT48
J 0
(-1240 4410);
DISPLAY 0.489362 (-1240 4410);
PAINT MONO (-1240 4410);
FORCEPROP 0 LASTPIN (-1250 4450) $PN CT49
J 0
(-1240 4460);
DISPLAY 0.489362 (-1240 4460);
PAINT MONO (-1240 4460);
FORCEPROP 0 LASTPIN (-1250 4500) $PN CT50
J 0
(-1240 4510);
DISPLAY 0.489362 (-1240 4510);
PAINT MONO (-1240 4510);
FORCEPROP 0 LASTPIN (-1250 4550) $PN CT51
J 0
(-1240 4560);
DISPLAY 0.489362 (-1240 4560);
PAINT MONO (-1240 4560);
FORCEPROP 0 LASTPIN (-1250 4600) $PN CT53
J 0
(-1240 4610);
DISPLAY 0.489362 (-1240 4610);
PAINT MONO (-1240 4610);
FORCEPROP 0 LASTPIN (-1250 4650) $PN CT59
J 0
(-1240 4660);
DISPLAY 0.489362 (-1240 4660);
PAINT MONO (-1240 4660);
FORCEPROP 0 LASTPIN (-1250 4700) $PN CT61
J 0
(-1240 4710);
DISPLAY 0.489362 (-1240 4710);
PAINT MONO (-1240 4710);
FORCEPROP 0 LASTPIN (-1250 4750) $PN CT66
J 0
(-1240 4760);
DISPLAY 0.489362 (-1240 4760);
PAINT MONO (-1240 4760);
FORCEPROP 0 LASTPIN (-1250 4800) $PN CT68
J 0
(-1240 4810);
DISPLAY 0.489362 (-1240 4810);
PAINT MONO (-1240 4810);
FORCEPROP 0 LASTPIN (-1250 4850) $PN CT73
J 0
(-1240 4860);
DISPLAY 0.489362 (-1240 4860);
PAINT MONO (-1240 4860);
FORCEPROP 0 LASTPIN (-1250 4900) $PN CU1
J 0
(-1240 4910);
DISPLAY 0.489362 (-1240 4910);
PAINT MONO (-1240 4910);
FORCEPROP 0 LASTPIN (-1250 4950) $PN CU4
J 0
(-1240 4960);
DISPLAY 0.489362 (-1240 4960);
PAINT MONO (-1240 4960);
FORCEPROP 0 LASTPIN (-1250 5000) $PN CU6
J 0
(-1240 5010);
DISPLAY 0.489362 (-1240 5010);
PAINT MONO (-1240 5010);
FORCEPROP 0 LASTPIN (-1250 5050) $PN CU8
J 0
(-1240 5060);
DISPLAY 0.489362 (-1240 5060);
PAINT MONO (-1240 5060);
FORCEPROP 0 LASTPIN (-1250 5100) $PN CU11
J 0
(-1240 5110);
DISPLAY 0.489362 (-1240 5110);
PAINT MONO (-1240 5110);
FORCEPROP 0 LASTPIN (-1250 5150) $PN CU13
J 0
(-1240 5160);
DISPLAY 0.489362 (-1240 5160);
PAINT MONO (-1240 5160);
FORCEPROP 0 LASTPIN (-1250 5200) $PN CU15
J 0
(-1240 5210);
DISPLAY 0.489362 (-1240 5210);
PAINT MONO (-1240 5210);
FORCEPROP 0 LASTPIN (-1250 5250) $PN CU18
J 0
(-1240 5260);
DISPLAY 0.489362 (-1240 5260);
PAINT MONO (-1240 5260);
FORCEPROP 0 LASTPIN (-1250 5300) $PN CU20
J 0
(-1240 5310);
DISPLAY 0.489362 (-1240 5310);
PAINT MONO (-1240 5310);
FORCEPROP 0 LASTPIN (-1250 5350) $PN CU22
J 0
(-1240 5360);
DISPLAY 0.489362 (-1240 5360);
PAINT MONO (-1240 5360);
FORCEPROP 0 LASTPIN (-1250 5400) $PN CU25
J 0
(-1240 5410);
DISPLAY 0.489362 (-1240 5410);
PAINT MONO (-1240 5410);
FORCEPROP 0 LASTPIN (-1250 5450) $PN CU28
J 0
(-1240 5460);
DISPLAY 0.489362 (-1240 5460);
PAINT MONO (-1240 5460);
FORCEPROP 0 LASTPIN (-1250 5500) $PN CU31
J 0
(-1240 5510);
DISPLAY 0.489362 (-1240 5510);
PAINT MONO (-1240 5510);
FORCEPROP 0 LASTPIN (-1250 5550) $PN CU34
J 0
(-1240 5560);
DISPLAY 0.489362 (-1240 5560);
PAINT MONO (-1240 5560);
FORCEPROP 0 LASTPIN (-1250 5600) $PN CU42
J 0
(-1240 5610);
DISPLAY 0.489362 (-1240 5610);
PAINT MONO (-1240 5610);
FORCEPROP 0 LASTPIN (-1250 5650) $PN CU45
J 0
(-1240 5660);
DISPLAY 0.489362 (-1240 5660);
PAINT MONO (-1240 5660);
FORCEPROP 0 LASTPIN (-1250 5700) $PN CU48
J 0
(-1240 5710);
DISPLAY 0.489362 (-1240 5710);
PAINT MONO (-1240 5710);
FORCEPROP 0 LASTPIN (-1250 5750) $PN CU51
J 0
(-1240 5760);
DISPLAY 0.489362 (-1240 5760);
PAINT MONO (-1240 5760);
FORCEPROP 0 LASTPIN (-1250 5800) $PN CU54
J 0
(-1240 5810);
DISPLAY 0.489362 (-1240 5810);
PAINT MONO (-1240 5810);
FORCEPROP 0 LASTPIN (-1250 5850) $PN CU56
J 0
(-1240 5860);
DISPLAY 0.489362 (-1240 5860);
PAINT MONO (-1240 5860);
FORCEPROP 0 LASTPIN (-1250 5900) $PN CU61
J 0
(-1240 5910);
DISPLAY 0.489362 (-1240 5910);
PAINT MONO (-1240 5910);
FORCEPROP 0 LASTPIN (-1250 5950) $PN CU63
J 0
(-1240 5960);
DISPLAY 0.489362 (-1240 5960);
PAINT MONO (-1240 5960);
FORCEPROP 0 LASTPIN (-1250 6000) $PN CU65
J 0
(-1240 6010);
DISPLAY 0.489362 (-1240 6010);
PAINT MONO (-1240 6010);
FORCEPROP 0 LASTPIN (-1250 6050) $PN CU68
J 0
(-1240 6060);
DISPLAY 0.489362 (-1240 6060);
PAINT MONO (-1240 6060);
FORCEPROP 0 LASTPIN (-1250 6100) $PN CU70
J 0
(-1240 6110);
DISPLAY 0.489362 (-1240 6110);
PAINT MONO (-1240 6110);
FORCEPROP 0 LASTPIN (-1250 6150) $PN CU72
J 0
(-1240 6160);
DISPLAY 0.489362 (-1240 6160);
PAINT MONO (-1240 6160);
FORCEPROP 0 LASTPIN (-1250 6200) $PN CU75
J 0
(-1240 6210);
DISPLAY 0.489362 (-1240 6210);
PAINT MONO (-1240 6210);
FORCEPROP 0 LASTPIN (-1250 6250) $PN CV3
J 0
(-1240 6260);
DISPLAY 0.489362 (-1240 6260);
PAINT MONO (-1240 6260);
FORCEPROP 0 LASTPIN (-1250 6300) $PN CV5
J 0
(-1240 6310);
DISPLAY 0.489362 (-1240 6310);
PAINT MONO (-1240 6310);
FORCEPROP 0 LASTPIN (-1250 6350) $PN CV8
J 0
(-1240 6360);
DISPLAY 0.489362 (-1240 6360);
PAINT MONO (-1240 6360);
FORCEPROP 0 LASTPIN (-2350 550) $PN CV10
J 2
(-2360 560);
DISPLAY 0.489362 (-2360 560);
PAINT MONO (-2360 560);
FORCEPROP 0 LASTPIN (-2350 600) $PN CV12
J 2
(-2360 610);
DISPLAY 0.489362 (-2360 610);
PAINT MONO (-2360 610);
FORCEPROP 0 LASTPIN (-2350 650) $PN CV15
J 2
(-2360 660);
DISPLAY 0.489362 (-2360 660);
PAINT MONO (-2360 660);
FORCEPROP 0 LASTPIN (-2350 700) $PN CV17
J 2
(-2360 710);
DISPLAY 0.489362 (-2360 710);
PAINT MONO (-2360 710);
FORCEPROP 0 LASTPIN (-2350 750) $PN CV19
J 2
(-2360 760);
DISPLAY 0.489362 (-2360 760);
PAINT MONO (-2360 760);
FORCEPROP 0 LASTPIN (-2350 800) $PN CV22
J 2
(-2360 810);
DISPLAY 0.489362 (-2360 810);
PAINT MONO (-2360 810);
FORCEPROP 0 LASTPIN (-2350 850) $PN CV25
J 2
(-2360 860);
DISPLAY 0.489362 (-2360 860);
PAINT MONO (-2360 860);
FORCEPROP 0 LASTPIN (-2350 900) $PN CV28
J 2
(-2360 910);
DISPLAY 0.489362 (-2360 910);
PAINT MONO (-2360 910);
FORCEPROP 0 LASTPIN (-2350 950) $PN CV31
J 2
(-2360 960);
DISPLAY 0.489362 (-2360 960);
PAINT MONO (-2360 960);
FORCEPROP 0 LASTPIN (-2350 1000) $PN CV34
J 2
(-2360 1010);
DISPLAY 0.489362 (-2360 1010);
PAINT MONO (-2360 1010);
FORCEPROP 0 LASTPIN (-2350 1050) $PN CV37
J 2
(-2360 1060);
DISPLAY 0.489362 (-2360 1060);
PAINT MONO (-2360 1060);
FORCEPROP 0 LASTPIN (-2350 1100) $PN CV39
J 2
(-2360 1110);
DISPLAY 0.489362 (-2360 1110);
PAINT MONO (-2360 1110);
FORCEPROP 0 LASTPIN (-2350 1150) $PN CV42
J 2
(-2360 1160);
DISPLAY 0.489362 (-2360 1160);
PAINT MONO (-2360 1160);
FORCEPROP 0 LASTPIN (-2350 1200) $PN CV45
J 2
(-2360 1210);
DISPLAY 0.489362 (-2360 1210);
PAINT MONO (-2360 1210);
FORCEPROP 0 LASTPIN (-2350 1250) $PN CV48
J 2
(-2360 1260);
DISPLAY 0.489362 (-2360 1260);
PAINT MONO (-2360 1260);
FORCEPROP 0 LASTPIN (-2350 1300) $PN CV51
J 2
(-2360 1310);
DISPLAY 0.489362 (-2360 1310);
PAINT MONO (-2360 1310);
FORCEPROP 0 LASTPIN (-2350 1350) $PN CV54
J 2
(-2360 1360);
DISPLAY 0.489362 (-2360 1360);
PAINT MONO (-2360 1360);
FORCEPROP 0 LASTPIN (-2350 1400) $PN CV57
J 2
(-2360 1410);
DISPLAY 0.489362 (-2360 1410);
PAINT MONO (-2360 1410);
FORCEPROP 0 LASTPIN (-2350 1450) $PN CV59
J 2
(-2360 1460);
DISPLAY 0.489362 (-2360 1460);
PAINT MONO (-2360 1460);
FORCEPROP 0 LASTPIN (-2350 1500) $PN CV61
J 2
(-2360 1510);
DISPLAY 0.489362 (-2360 1510);
PAINT MONO (-2360 1510);
FORCEPROP 0 LASTPIN (-2350 1550) $PN CV64
J 2
(-2360 1560);
DISPLAY 0.489362 (-2360 1560);
PAINT MONO (-2360 1560);
FORCEPROP 0 LASTPIN (-2350 1600) $PN CV66
J 2
(-2360 1610);
DISPLAY 0.489362 (-2360 1610);
PAINT MONO (-2360 1610);
FORCEPROP 0 LASTPIN (-2350 1650) $PN CV68
J 2
(-2360 1660);
DISPLAY 0.489362 (-2360 1660);
PAINT MONO (-2360 1660);
FORCEPROP 0 LASTPIN (-2350 1700) $PN CV71
J 2
(-2360 1710);
DISPLAY 0.489362 (-2360 1710);
PAINT MONO (-2360 1710);
FORCEPROP 0 LASTPIN (-2350 1750) $PN CV73
J 2
(-2360 1760);
DISPLAY 0.489362 (-2360 1760);
PAINT MONO (-2360 1760);
FORCEPROP 0 LASTPIN (-2350 1800) $PN CW1
J 2
(-2360 1810);
DISPLAY 0.489362 (-2360 1810);
PAINT MONO (-2360 1810);
FORCEPROP 0 LASTPIN (-2350 1850) $PN CW6
J 2
(-2360 1860);
DISPLAY 0.489362 (-2360 1860);
PAINT MONO (-2360 1860);
FORCEPROP 0 LASTPIN (-2350 1900) $PN CW8
J 2
(-2360 1910);
DISPLAY 0.489362 (-2360 1910);
PAINT MONO (-2360 1910);
FORCEPROP 0 LASTPIN (-2350 1950) $PN CW13
J 2
(-2360 1960);
DISPLAY 0.489362 (-2360 1960);
PAINT MONO (-2360 1960);
FORCEPROP 0 LASTPIN (-2350 2000) $PN CW15
J 2
(-2360 2010);
DISPLAY 0.489362 (-2360 2010);
PAINT MONO (-2360 2010);
FORCEPROP 0 LASTPIN (-2350 2050) $PN CW20
J 2
(-2360 2060);
DISPLAY 0.489362 (-2360 2060);
PAINT MONO (-2360 2060);
FORCEPROP 0 LASTPIN (-2350 2100) $PN CW22
J 2
(-2360 2110);
DISPLAY 0.489362 (-2360 2110);
PAINT MONO (-2360 2110);
FORCEPROP 0 LASTPIN (-2350 2150) $PN CW25
J 2
(-2360 2160);
DISPLAY 0.489362 (-2360 2160);
PAINT MONO (-2360 2160);
FORCEPROP 0 LASTPIN (-2350 2200) $PN CW28
J 2
(-2360 2210);
DISPLAY 0.489362 (-2360 2210);
PAINT MONO (-2360 2210);
FORCEPROP 0 LASTPIN (-2350 2250) $PN CW31
J 2
(-2360 2260);
DISPLAY 0.489362 (-2360 2260);
PAINT MONO (-2360 2260);
FORCEPROP 0 LASTPIN (-2350 2300) $PN CW34
J 2
(-2360 2310);
DISPLAY 0.489362 (-2360 2310);
PAINT MONO (-2360 2310);
FORCEPROP 0 LASTPIN (-2350 2350) $PN CW35
J 2
(-2360 2360);
DISPLAY 0.489362 (-2360 2360);
PAINT MONO (-2360 2360);
FORCEPROP 0 LASTPIN (-2350 2400) $PN CW36
J 2
(-2360 2410);
DISPLAY 0.489362 (-2360 2410);
PAINT MONO (-2360 2410);
FORCEPROP 0 LASTPIN (-2350 2450) $PN CW40
J 2
(-2360 2460);
DISPLAY 0.489362 (-2360 2460);
PAINT MONO (-2360 2460);
FORCEPROP 0 LASTPIN (-2350 2500) $PN CW41
J 2
(-2360 2510);
DISPLAY 0.489362 (-2360 2510);
PAINT MONO (-2360 2510);
FORCEPROP 0 LASTPIN (-2350 2550) $PN CW42
J 2
(-2360 2560);
DISPLAY 0.489362 (-2360 2560);
PAINT MONO (-2360 2560);
FORCEPROP 0 LASTPIN (-2350 2600) $PN CW45
J 2
(-2360 2610);
DISPLAY 0.489362 (-2360 2610);
PAINT MONO (-2360 2610);
FORCEPROP 0 LASTPIN (-2350 2650) $PN CW48
J 2
(-2360 2660);
DISPLAY 0.489362 (-2360 2660);
PAINT MONO (-2360 2660);
FORCEPROP 0 LASTPIN (-2350 2700) $PN CW51
J 2
(-2360 2710);
DISPLAY 0.489362 (-2360 2710);
PAINT MONO (-2360 2710);
FORCEPROP 0 LASTPIN (-2350 2750) $PN CW54
J 2
(-2360 2760);
DISPLAY 0.489362 (-2360 2760);
PAINT MONO (-2360 2760);
FORCEPROP 0 LASTPIN (-2350 2800) $PN CW56
J 2
(-2360 2810);
DISPLAY 0.489362 (-2360 2810);
PAINT MONO (-2360 2810);
FORCEPROP 0 LASTPIN (-2350 2850) $PN CW61
J 2
(-2360 2860);
DISPLAY 0.489362 (-2360 2860);
PAINT MONO (-2360 2860);
FORCEPROP 0 LASTPIN (-2350 2900) $PN CW63
J 2
(-2360 2910);
DISPLAY 0.489362 (-2360 2910);
PAINT MONO (-2360 2910);
FORCEPROP 0 LASTPIN (-2350 2950) $PN CW68
J 2
(-2360 2960);
DISPLAY 0.489362 (-2360 2960);
PAINT MONO (-2360 2960);
FORCEPROP 0 LASTPIN (-2350 3000) $PN CW70
J 2
(-2360 3010);
DISPLAY 0.489362 (-2360 3010);
PAINT MONO (-2360 3010);
FORCEPROP 0 LASTPIN (-2350 3050) $PN CW75
J 2
(-2360 3060);
DISPLAY 0.489362 (-2360 3060);
PAINT MONO (-2360 3060);
FORCEPROP 0 LASTPIN (-2350 3100) $PN CY3
J 2
(-2360 3110);
DISPLAY 0.489362 (-2360 3110);
PAINT MONO (-2360 3110);
FORCEPROP 0 LASTPIN (-2350 3150) $PN CY5
J 2
(-2360 3160);
DISPLAY 0.489362 (-2360 3160);
PAINT MONO (-2360 3160);
FORCEPROP 0 LASTPIN (-2350 3200) $PN CY8
J 2
(-2360 3210);
DISPLAY 0.489362 (-2360 3210);
PAINT MONO (-2360 3210);
FORCEPROP 0 LASTPIN (-2350 3250) $PN CY10
J 2
(-2360 3260);
DISPLAY 0.489362 (-2360 3260);
PAINT MONO (-2360 3260);
FORCEPROP 0 LASTPIN (-2350 3300) $PN CY12
J 2
(-2360 3310);
DISPLAY 0.489362 (-2360 3310);
PAINT MONO (-2360 3310);
FORCEPROP 0 LASTPIN (-2350 3350) $PN CY15
J 2
(-2360 3360);
DISPLAY 0.489362 (-2360 3360);
PAINT MONO (-2360 3360);
FORCEPROP 0 LASTPIN (-2350 3400) $PN CY17
J 2
(-2360 3410);
DISPLAY 0.489362 (-2360 3410);
PAINT MONO (-2360 3410);
FORCEPROP 0 LASTPIN (-2350 3450) $PN CY19
J 2
(-2360 3460);
DISPLAY 0.489362 (-2360 3460);
PAINT MONO (-2360 3460);
FORCEPROP 0 LASTPIN (-2350 3500) $PN CY23
J 2
(-2360 3510);
DISPLAY 0.489362 (-2360 3510);
PAINT MONO (-2360 3510);
FORCEPROP 0 LASTPIN (-2350 3550) $PN CY24
J 2
(-2360 3560);
DISPLAY 0.489362 (-2360 3560);
PAINT MONO (-2360 3560);
FORCEPROP 0 LASTPIN (-2350 3600) $PN CY25
J 2
(-2360 3610);
DISPLAY 0.489362 (-2360 3610);
PAINT MONO (-2360 3610);
FORCEPROP 0 LASTPIN (-2350 3650) $PN CY26
J 2
(-2360 3660);
DISPLAY 0.489362 (-2360 3660);
PAINT MONO (-2360 3660);
FORCEPROP 0 LASTPIN (-2350 3700) $PN CY27
J 2
(-2360 3710);
DISPLAY 0.489362 (-2360 3710);
PAINT MONO (-2360 3710);
FORCEPROP 0 LASTPIN (-2350 3750) $PN CY28
J 2
(-2360 3760);
DISPLAY 0.489362 (-2360 3760);
PAINT MONO (-2360 3760);
FORCEPROP 0 LASTPIN (-2350 3800) $PN CY29
J 2
(-2360 3810);
DISPLAY 0.489362 (-2360 3810);
PAINT MONO (-2360 3810);
FORCEPROP 0 LASTPIN (-2350 3850) $PN CY30
J 2
(-2360 3860);
DISPLAY 0.489362 (-2360 3860);
PAINT MONO (-2360 3860);
FORCEPROP 0 LASTPIN (-2350 3900) $PN CY31
J 2
(-2360 3910);
DISPLAY 0.489362 (-2360 3910);
PAINT MONO (-2360 3910);
FORCEPROP 0 LASTPIN (-2350 3950) $PN CY32
J 2
(-2360 3960);
DISPLAY 0.489362 (-2360 3960);
PAINT MONO (-2360 3960);
FORCEPROP 0 LASTPIN (-2350 4000) $PN CY33
J 2
(-2360 4010);
DISPLAY 0.489362 (-2360 4010);
PAINT MONO (-2360 4010);
FORCEPROP 0 LASTPIN (-2350 4050) $PN CY34
J 2
(-2360 4060);
DISPLAY 0.489362 (-2360 4060);
PAINT MONO (-2360 4060);
FORCEPROP 0 LASTPIN (-2350 4100) $PN CY37
J 2
(-2360 4110);
DISPLAY 0.489362 (-2360 4110);
PAINT MONO (-2360 4110);
FORCEPROP 0 LASTPIN (-2350 4150) $PN CY39
J 2
(-2360 4160);
DISPLAY 0.489362 (-2360 4160);
PAINT MONO (-2360 4160);
FORCEPROP 0 LASTPIN (-2350 4200) $PN CY42
J 2
(-2360 4210);
DISPLAY 0.489362 (-2360 4210);
PAINT MONO (-2360 4210);
FORCEPROP 0 LASTPIN (-2350 4250) $PN CY43
J 2
(-2360 4260);
DISPLAY 0.489362 (-2360 4260);
PAINT MONO (-2360 4260);
FORCEPROP 0 LASTPIN (-2350 4300) $PN CY44
J 2
(-2360 4310);
DISPLAY 0.489362 (-2360 4310);
PAINT MONO (-2360 4310);
FORCEPROP 0 LASTPIN (-2350 4350) $PN CY45
J 2
(-2360 4360);
DISPLAY 0.489362 (-2360 4360);
PAINT MONO (-2360 4360);
FORCEPROP 0 LASTPIN (-2350 4400) $PN CY46
J 2
(-2360 4410);
DISPLAY 0.489362 (-2360 4410);
PAINT MONO (-2360 4410);
FORCEPROP 0 LASTPIN (-2350 4450) $PN CY47
J 2
(-2360 4460);
DISPLAY 0.489362 (-2360 4460);
PAINT MONO (-2360 4460);
FORCEPROP 0 LASTPIN (-2350 4500) $PN CY48
J 2
(-2360 4510);
DISPLAY 0.489362 (-2360 4510);
PAINT MONO (-2360 4510);
FORCEPROP 0 LASTPIN (-2350 4550) $PN CY49
J 2
(-2360 4560);
DISPLAY 0.489362 (-2360 4560);
PAINT MONO (-2360 4560);
FORCEPROP 0 LASTPIN (-2350 4600) $PN CY50
J 2
(-2360 4610);
DISPLAY 0.489362 (-2360 4610);
PAINT MONO (-2360 4610);
FORCEPROP 0 LASTPIN (-2350 4650) $PN CY51
J 2
(-2360 4660);
DISPLAY 0.489362 (-2360 4660);
PAINT MONO (-2360 4660);
FORCEPROP 0 LASTPIN (-2350 4700) $PN CY52
J 2
(-2360 4710);
DISPLAY 0.489362 (-2360 4710);
PAINT MONO (-2360 4710);
FORCEPROP 0 LASTPIN (-2350 4750) $PN CY53
J 2
(-2360 4760);
DISPLAY 0.489362 (-2360 4760);
PAINT MONO (-2360 4760);
FORCEPROP 0 LASTPIN (-2350 4800) $PN CY59
J 2
(-2360 4810);
DISPLAY 0.489362 (-2360 4810);
PAINT MONO (-2360 4810);
FORCEPROP 0 LASTPIN (-2350 4850) $PN CY61
J 2
(-2360 4860);
DISPLAY 0.489362 (-2360 4860);
PAINT MONO (-2360 4860);
FORCEPROP 0 LASTPIN (-2350 4900) $PN CY64
J 2
(-2360 4910);
DISPLAY 0.489362 (-2360 4910);
PAINT MONO (-2360 4910);
FORCEPROP 0 LASTPIN (-2350 4950) $PN CY66
J 2
(-2360 4960);
DISPLAY 0.489362 (-2360 4960);
PAINT MONO (-2360 4960);
FORCEPROP 0 LASTPIN (-2350 5000) $PN CY68
J 2
(-2360 5010);
DISPLAY 0.489362 (-2360 5010);
PAINT MONO (-2360 5010);
FORCEPROP 0 LASTPIN (-2350 5050) $PN CY71
J 2
(-2360 5060);
DISPLAY 0.489362 (-2360 5060);
PAINT MONO (-2360 5060);
FORCEPROP 0 LASTPIN (-2350 5100) $PN CY73
J 2
(-2360 5110);
DISPLAY 0.489362 (-2360 5110);
PAINT MONO (-2360 5110);
FORCEPROP 0 LASTPIN (-2350 5150) $PN DA1
J 2
(-2360 5160);
DISPLAY 0.489362 (-2360 5160);
PAINT MONO (-2360 5160);
FORCEPROP 0 LASTPIN (-2350 5200) $PN DA4
J 2
(-2360 5210);
DISPLAY 0.489362 (-2360 5210);
PAINT MONO (-2360 5210);
FORCEPROP 0 LASTPIN (-2350 5250) $PN DA6
J 2
(-2360 5260);
DISPLAY 0.489362 (-2360 5260);
PAINT MONO (-2360 5260);
FORCEPROP 0 LASTPIN (-2350 5300) $PN DA8
J 2
(-2360 5310);
DISPLAY 0.489362 (-2360 5310);
PAINT MONO (-2360 5310);
FORCEPROP 0 LASTPIN (-2350 5350) $PN DA11
J 2
(-2360 5360);
DISPLAY 0.489362 (-2360 5360);
PAINT MONO (-2360 5360);
FORCEPROP 0 LASTPIN (-2350 5400) $PN DA13
J 2
(-2360 5410);
DISPLAY 0.489362 (-2360 5410);
PAINT MONO (-2360 5410);
FORCEPROP 0 LASTPIN (-2350 5450) $PN DA15
J 2
(-2360 5460);
DISPLAY 0.489362 (-2360 5460);
PAINT MONO (-2360 5460);
FORCEPROP 0 LASTPIN (-2350 5500) $PN DA18
J 2
(-2360 5510);
DISPLAY 0.489362 (-2360 5510);
PAINT MONO (-2360 5510);
FORCEPROP 0 LASTPIN (-2350 5550) $PN DA20
J 2
(-2360 5560);
DISPLAY 0.489362 (-2360 5560);
PAINT MONO (-2360 5560);
FORCEPROP 0 LASTPIN (-2350 5600) $PN DA22
J 2
(-2360 5610);
DISPLAY 0.489362 (-2360 5610);
PAINT MONO (-2360 5610);
FORCEPROP 0 LASTPIN (-2350 5650) $PN DA25
J 2
(-2360 5660);
DISPLAY 0.489362 (-2360 5660);
PAINT MONO (-2360 5660);
FORCEPROP 0 LASTPIN (-2350 5700) $PN DA28
J 2
(-2360 5710);
DISPLAY 0.489362 (-2360 5710);
PAINT MONO (-2360 5710);
FORCEPROP 0 LASTPIN (-2350 5750) $PN DA31
J 2
(-2360 5760);
DISPLAY 0.489362 (-2360 5760);
PAINT MONO (-2360 5760);
FORCEPROP 0 LASTPIN (-2350 5800) $PN DA34
J 2
(-2360 5810);
DISPLAY 0.489362 (-2360 5810);
PAINT MONO (-2360 5810);
FORCEPROP 0 LASTPIN (-2350 5850) $PN DA42
J 2
(-2360 5860);
DISPLAY 0.489362 (-2360 5860);
PAINT MONO (-2360 5860);
FORCEPROP 0 LASTPIN (-2350 5900) $PN DA45
J 2
(-2360 5910);
DISPLAY 0.489362 (-2360 5910);
PAINT MONO (-2360 5910);
FORCEPROP 0 LASTPIN (-2350 5950) $PN DA48
J 2
(-2360 5960);
DISPLAY 0.489362 (-2360 5960);
PAINT MONO (-2360 5960);
FORCEPROP 0 LASTPIN (-2350 6000) $PN DA51
J 2
(-2360 6010);
DISPLAY 0.489362 (-2360 6010);
PAINT MONO (-2360 6010);
FORCEPROP 0 LASTPIN (-2350 6050) $PN DA54
J 2
(-2360 6060);
DISPLAY 0.489362 (-2360 6060);
PAINT MONO (-2360 6060);
FORCEPROP 0 LASTPIN (-2350 6100) $PN DA58
J 2
(-2360 6110);
DISPLAY 0.489362 (-2360 6110);
PAINT MONO (-2360 6110);
FORCEPROP 0 LASTPIN (-2350 6150) $PN DA61
J 2
(-2360 6160);
DISPLAY 0.489362 (-2360 6160);
PAINT MONO (-2360 6160);
FORCEPROP 0 LASTPIN (-2350 6200) $PN DA63
J 2
(-2360 6210);
DISPLAY 0.489362 (-2360 6210);
PAINT MONO (-2360 6210);
FORCEPROP 0 LASTPIN (-2350 6250) $PN DA65
J 2
(-2360 6260);
DISPLAY 0.489362 (-2360 6260);
PAINT MONO (-2360 6260);
FORCEPROP 0 LASTPIN (-2350 6300) $PN DA68
J 2
(-2360 6310);
DISPLAY 0.489362 (-2360 6310);
PAINT MONO (-2360 6310);
FORCEPROP 0 LASTPIN (-2350 6350) $PN DA70
J 2
(-2360 6360);
DISPLAY 0.489362 (-2360 6360);
PAINT MONO (-2360 6360);
FORCEPROP 2 LAST PART_TYPE SMLF
J 0
(-2425 6700);
DISPLAY 1.021277 (-2425 6700);
FORCEPROP 1 LAST MATERIAL IO
J 0
(-2195 6582);
DISPLAY 0.489362 (-2195 6582);
PAINT SKYBLUE (-2195 6582);
FORCEPROP 2 LAST VALUE SOCKET6096_13568-001
J 0
(-2200 6625);
DISPLAY 0.489362 (-2200 6625);
PAINT SKYBLUE (-2200 6625);
FORCEPROP 1 LAST PART_NUMBER DGA^6000030
J 0
(-2195 6709);
DISPLAY 0.489362 (-2195 6709);
PAINT SKYBLUE (-2195 6709);
FORCEPROP 2 LAST CDS_LIB pure_quanta
J 0
(-1800 3500);
DISPLAY INVISIBLE (-1800 3500);
FORCEPROP 1 LAST CDS_LMAN_SYM_OUTLINE -400,3050,400,-3050
J 0
(-1800 3500);
DISPLAY 0.468085 (-1800 3500);
PAINT GREEN (-1800 3500);
DISPLAY INVISIBLE (-1800 3500);
FORCEPROP 1 LAST NEEDS_NO_SIZE TRUE
J 0
(-1800 3500);
DISPLAY 0.723404 (-1800 3500);
PAINT GREEN (-1800 3500);
DISPLAY INVISIBLE (-1800 3500);
FORCEPROP 1 LAST PATH I4
J 0
(-1800 3500);
DISPLAY 0.723404 (-1800 3500);
PAINT GREEN (-1800 3500);
DISPLAY INVISIBLE (-1800 3500);
FORCEADD UNIVERSAL_GND..1
(-1075 450);
FORCEPROP 3 LASTPIN (-1075 500) SIG_NAME GND\g
J 0
(-1065 510);
DISPLAY 0.659574 (-1065 510);
PAINT MONO (-1065 510);
DISPLAY INVISIBLE (-1065 510);
FORCEPROP 2 LAST CDS_LIB pure_quanta_power
J 0
(-1075 450);
DISPLAY INVISIBLE (-1075 450);
FORCEPROP 1 LAST PATH I5
J 0
(-1000 450);
DISPLAY 0.872340 (-1000 450);
PAINT AQUA (-1000 450);
DISPLAY INVISIBLE (-1000 450);
FORCEPROP 1 LAST HDL_POWER GND
J 1
(-1050 375);
DISPLAY 0.872340 (-1050 375);
PAINT GREEN (-1050 375);
DISPLAY INVISIBLE (-1050 375);
FORCEADD UNIVERSAL_GND..1
(-2525 450);
FORCEPROP 3 LASTPIN (-2525 500) SIG_NAME GND\g
J 0
(-2515 510);
DISPLAY 0.659574 (-2515 510);
PAINT MONO (-2515 510);
DISPLAY INVISIBLE (-2515 510);
FORCEPROP 2 LAST CDS_LIB pure_quanta_power
J 0
(-2525 450);
DISPLAY INVISIBLE (-2525 450);
FORCEPROP 1 LAST PATH I6
J 0
(-2450 450);
DISPLAY 0.872340 (-2450 450);
PAINT AQUA (-2450 450);
DISPLAY INVISIBLE (-2450 450);
FORCEPROP 1 LAST HDL_POWER GND
J 1
(-2500 375);
DISPLAY 0.872340 (-2500 375);
PAINT GREEN (-2500 375);
DISPLAY INVISIBLE (-2500 375);
FORCEADD UNIVERSAL_GND..1
(-3150 450);
FORCEPROP 3 LASTPIN (-3150 500) SIG_NAME GND\g
J 0
(-3140 510);
DISPLAY 0.659574 (-3140 510);
PAINT MONO (-3140 510);
DISPLAY INVISIBLE (-3140 510);
FORCEPROP 2 LAST CDS_LIB pure_quanta_power
J 0
(-3150 450);
DISPLAY INVISIBLE (-3150 450);
FORCEPROP 1 LAST PATH I7
J 0
(-3075 450);
DISPLAY 0.872340 (-3075 450);
PAINT AQUA (-3075 450);
DISPLAY INVISIBLE (-3075 450);
FORCEPROP 1 LAST HDL_POWER GND
J 1
(-3125 375);
DISPLAY 0.872340 (-3125 375);
PAINT GREEN (-3125 375);
DISPLAY INVISIBLE (-3125 375);
FORCEADD UNIVERSAL_GND..1
(-4600 475);
FORCEPROP 3 LASTPIN (-4600 525) SIG_NAME GND\g
J 0
(-4590 535);
DISPLAY 0.659574 (-4590 535);
PAINT MONO (-4590 535);
DISPLAY INVISIBLE (-4590 535);
FORCEPROP 2 LAST CDS_LIB pure_quanta_power
J 0
(-4600 475);
DISPLAY INVISIBLE (-4600 475);
FORCEPROP 1 LAST PATH I8
J 0
(-4525 475);
DISPLAY 0.872340 (-4525 475);
PAINT AQUA (-4525 475);
DISPLAY INVISIBLE (-4525 475);
FORCEPROP 1 LAST HDL_POWER GND
J 1
(-4575 400);
DISPLAY 0.872340 (-4575 400);
PAINT GREEN (-4575 400);
DISPLAY INVISIBLE (-4575 400);
FORCEADD UNIVERSAL_GND..1
(-5225 475);
FORCEPROP 3 LASTPIN (-5225 525) SIG_NAME GND\g
J 0
(-5215 535);
DISPLAY 0.659574 (-5215 535);
PAINT MONO (-5215 535);
DISPLAY INVISIBLE (-5215 535);
FORCEPROP 2 LAST CDS_LIB pure_quanta_power
J 0
(-5225 475);
DISPLAY INVISIBLE (-5225 475);
FORCEPROP 1 LAST PATH I9
J 0
(-5150 475);
DISPLAY 0.872340 (-5150 475);
PAINT AQUA (-5150 475);
DISPLAY INVISIBLE (-5150 475);
FORCEPROP 1 LAST HDL_POWER GND
J 1
(-5200 400);
DISPLAY 0.872340 (-5200 400);
PAINT GREEN (-5200 400);
DISPLAY INVISIBLE (-5200 400);
FORCEADD QUANTA_TITLE_BLOCK_C..1
(-100 100);
FORCEPROP 0 LAST CDS_CON_LAST_MODIFIED Fri Mar 11 14:52:42 2022
J 0
(-1985 115);
DISPLAY INVISIBLE (-1985 115);
FORCEPROP 1 LAST CUSTOM_TXT_CDS <CON_LAST_MODIFIED>
J 0
(-1985 115);
DISPLAY 0.978723 (-1985 115);
FORCEPROP 2 LAST CUSTOM_TXT_CDS <XR_PAGE_TITLE>
J 0
(-7990 5350);
DISPLAY 0.638298 (-7990 5350);
PAINT PINK (-7990 5350);
DISPLAY INVISIBLE (-7990 5350);
FORCEPROP 1 LAST CUSTOM_TXT_CDS <NAME_2>
J 0
(-3275 150);
FORCEPROP 1 LAST CUSTOM_TXT_CDS <NAME_1>
J 0
(-3275 275);
FORCEPROP 1 LAST CUSTOM_TXT_CDS <Q_NUMBER>
J 0
(-1503 203);
DISPLAY 1.212766 (-1503 203);
FORCEPROP 1 LAST CUSTOM_TXT_CDS <Q_PROJ>
J 0
(-2482 202);
DISPLAY 1.212766 (-2482 202);
FORCEPROP 1 LAST CUSTOM_TXT_CDS <Q_REV>
J 0
(-284 203);
DISPLAY 1.212766 (-284 203);
FORCEPROP 1 LAST CUSTOM_TXT_CDS <CON_PAGE_NUM> OF <CON_TOTAL_PAGES>
J 0
(-546 118);
DISPLAY 0.978723 (-546 118);
FORCEPROP 1 LAST Q_DEPT BU9
J 1
(-3863 149);
DISPLAY 1.957447 (-3863 149);
PAINT GREEN (-3863 149);
FORCEPROP 1 LAST Q_TITLE CPU1 VSS 2/3
J 0
(-9400 175);
DISPLAY 2.446809 (-9400 175);
PAINT GREEN (-9400 175);
FORCEPROP 2 LAST CDS_LIB pure_quanta
J 0
(-100 100);
DISPLAY INVISIBLE (-100 100);
FORCEPROP 1 LAST CDS_LMAN_SYM_OUTLINE -9475,6775,100,-125
J 0
(-100 100);
DISPLAY 0.468085 (-100 100);
PAINT GREEN (-100 100);
DISPLAY INVISIBLE (-100 100);
FORCEPROP 2 LAST PAGE_BORDER TRUE
J 0
(-7990 5350);
DISPLAY 0.638298 (-7990 5350);
PAINT PINK (-7990 5350);
DISPLAY INVISIBLE (-7990 5350);
FORCEPROP 1 LAST COMMENT_BODY TRUE
J 0
(-88 87);
DISPLAY 0.978723 (-88 87);
PAINT GREEN (-88 87);
DISPLAY INVISIBLE (-88 87);
FORCEPROP 2 LAST CDS_XR_PAGE_TITLE CR-59 : @T6G_MB_LIB.T6G(SCH_1):PAGE59
J 0
(-7990 5350);
DISPLAY 0.638298 (-7990 5350);
PAINT PINK (-7990 5350);
DISPLAY INVISIBLE (-7990 5350);
WIRE 16 -1 (-8525 550)(-8700 550);
WIRE 16 -1 (-8700 600)(-8700 550);
WIRE 16 -1 (-8700 550)(-8700 500);
WIRE 16 -1 (-8700 600)(-8525 600);
WIRE 16 -1 (-8700 650)(-8700 600);
WIRE 16 -1 (-8700 650)(-8525 650);
WIRE 16 -1 (-8700 700)(-8700 650);
WIRE 16 -1 (-8700 700)(-8525 700);
WIRE 16 -1 (-8700 750)(-8700 700);
WIRE 16 -1 (-8700 800)(-8700 750);
WIRE 16 -1 (-8700 750)(-8525 750);
WIRE 16 -1 (-8525 800)(-8700 800);
WIRE 16 -1 (-8700 850)(-8700 800);
WIRE 16 -1 (-8700 850)(-8525 850);
WIRE 16 -1 (-8700 900)(-8700 850);
WIRE 16 -1 (-8700 900)(-8525 900);
WIRE 16 -1 (-8700 950)(-8700 900);
WIRE 16 -1 (-8700 950)(-8525 950);
WIRE 16 -1 (-8700 1000)(-8700 950);
WIRE 16 -1 (-8700 1050)(-8700 1000);
WIRE 16 -1 (-8700 1000)(-8525 1000);
WIRE 16 -1 (-8525 1050)(-8700 1050);
WIRE 16 -1 (-8700 1100)(-8700 1050);
WIRE 16 -1 (-8700 1100)(-8525 1100);
WIRE 16 -1 (-8700 1150)(-8700 1100);
WIRE 16 -1 (-8700 1150)(-8525 1150);
WIRE 16 -1 (-8700 1200)(-8700 1150);
WIRE 16 -1 (-8700 1200)(-8525 1200);
WIRE 16 -1 (-8700 1250)(-8700 1200);
WIRE 16 -1 (-8700 1300)(-8700 1250);
WIRE 16 -1 (-8700 1250)(-8525 1250);
WIRE 16 -1 (-8525 1300)(-8700 1300);
WIRE 16 -1 (-8700 1350)(-8700 1300);
WIRE 16 -1 (-8700 1350)(-8525 1350);
WIRE 16 -1 (-8700 1400)(-8700 1350);
WIRE 16 -1 (-8700 1400)(-8525 1400);
WIRE 16 -1 (-8700 1450)(-8700 1400);
WIRE 16 -1 (-8700 1450)(-8525 1450);
WIRE 16 -1 (-8700 1500)(-8700 1450);
WIRE 16 -1 (-8700 1550)(-8700 1500);
WIRE 16 -1 (-8700 1500)(-8525 1500);
WIRE 16 -1 (-8525 1550)(-8700 1550);
WIRE 16 -1 (-8700 1600)(-8700 1550);
WIRE 16 -1 (-8700 1600)(-8525 1600);
WIRE 16 -1 (-8700 1650)(-8700 1600);
WIRE 16 -1 (-8700 1650)(-8525 1650);
WIRE 16 -1 (-8700 1700)(-8700 1650);
WIRE 16 -1 (-8700 1700)(-8525 1700);
WIRE 16 -1 (-8700 1750)(-8700 1700);
WIRE 16 -1 (-8700 1800)(-8700 1750);
WIRE 16 -1 (-8700 1750)(-8525 1750);
WIRE 16 -1 (-8525 1800)(-8700 1800);
WIRE 16 -1 (-8700 1850)(-8700 1800);
WIRE 16 -1 (-8700 1850)(-8525 1850);
WIRE 16 -1 (-8700 1900)(-8700 1850);
WIRE 16 -1 (-8700 1900)(-8525 1900);
WIRE 16 -1 (-8700 1950)(-8700 1900);
WIRE 16 -1 (-8700 1950)(-8525 1950);
WIRE 16 -1 (-8700 2000)(-8700 1950);
WIRE 16 -1 (-8700 2050)(-8700 2000);
WIRE 16 -1 (-8700 2000)(-8525 2000);
WIRE 16 -1 (-8525 2050)(-8700 2050);
WIRE 16 -1 (-8700 2100)(-8700 2050);
WIRE 16 -1 (-8700 2100)(-8525 2100);
WIRE 16 -1 (-8700 2150)(-8700 2100);
WIRE 16 -1 (-8700 2150)(-8525 2150);
WIRE 16 -1 (-8700 2200)(-8700 2150);
WIRE 16 -1 (-8700 2200)(-8525 2200);
WIRE 16 -1 (-8700 2250)(-8700 2200);
WIRE 16 -1 (-8700 2250)(-8525 2250);
WIRE 16 -1 (-8700 2300)(-8700 2250);
WIRE 16 -1 (-8700 2350)(-8700 2300);
WIRE 16 -1 (-8700 2300)(-8525 2300);
WIRE 16 -1 (-8525 2350)(-8700 2350);
WIRE 16 -1 (-8700 2400)(-8700 2350);
WIRE 16 -1 (-8700 2400)(-8525 2400);
WIRE 16 -1 (-8700 2450)(-8700 2400);
WIRE 16 -1 (-8700 2450)(-8525 2450);
WIRE 16 -1 (-8700 2500)(-8700 2450);
WIRE 16 -1 (-8700 2500)(-8525 2500);
WIRE 16 -1 (-8700 2550)(-8700 2500);
WIRE 16 -1 (-8700 2600)(-8700 2550);
WIRE 16 -1 (-8700 2550)(-8525 2550);
WIRE 16 -1 (-8525 2600)(-8700 2600);
WIRE 16 -1 (-8700 2650)(-8700 2600);
WIRE 16 -1 (-8700 2650)(-8525 2650);
WIRE 16 -1 (-8700 2700)(-8700 2650);
WIRE 16 -1 (-8700 2700)(-8525 2700);
WIRE 16 -1 (-8700 2750)(-8700 2700);
WIRE 16 -1 (-8700 2750)(-8525 2750);
WIRE 16 -1 (-8700 2800)(-8700 2750);
WIRE 16 -1 (-8700 2850)(-8700 2800);
WIRE 16 -1 (-8700 2800)(-8525 2800);
WIRE 16 -1 (-8525 2850)(-8700 2850);
WIRE 16 -1 (-8700 2900)(-8700 2850);
WIRE 16 -1 (-8700 2900)(-8525 2900);
WIRE 16 -1 (-8700 2950)(-8700 2900);
WIRE 16 -1 (-8700 2950)(-8525 2950);
WIRE 16 -1 (-8700 3000)(-8700 2950);
WIRE 16 -1 (-8700 3000)(-8525 3000);
WIRE 16 -1 (-8700 3050)(-8700 3000);
WIRE 16 -1 (-8700 3100)(-8700 3050);
WIRE 16 -1 (-8700 3050)(-8525 3050);
WIRE 16 -1 (-8525 3100)(-8700 3100);
WIRE 16 -1 (-8700 3150)(-8700 3100);
WIRE 16 -1 (-8700 3150)(-8525 3150);
WIRE 16 -1 (-8700 3200)(-8700 3150);
WIRE 16 -1 (-8700 3200)(-8525 3200);
WIRE 16 -1 (-8700 3250)(-8700 3200);
WIRE 16 -1 (-8700 3250)(-8525 3250);
WIRE 16 -1 (-8700 3300)(-8700 3250);
WIRE 16 -1 (-8700 3350)(-8700 3300);
WIRE 16 -1 (-8700 3300)(-8525 3300);
WIRE 16 -1 (-8525 3350)(-8700 3350);
WIRE 16 -1 (-8700 3400)(-8700 3350);
WIRE 16 -1 (-8700 3400)(-8525 3400);
WIRE 16 -1 (-8700 3450)(-8700 3400);
WIRE 16 -1 (-8700 3450)(-8525 3450);
WIRE 16 -1 (-8700 3500)(-8700 3450);
WIRE 16 -1 (-8700 3500)(-8525 3500);
WIRE 16 -1 (-8700 3550)(-8700 3500);
WIRE 16 -1 (-8700 3600)(-8700 3550);
WIRE 16 -1 (-8700 3550)(-8525 3550);
WIRE 16 -1 (-8525 3600)(-8700 3600);
WIRE 16 -1 (-8700 3650)(-8700 3600);
WIRE 16 -1 (-8700 3650)(-8525 3650);
WIRE 16 -1 (-8700 3700)(-8700 3650);
WIRE 16 -1 (-8700 3700)(-8525 3700);
WIRE 16 -1 (-8700 3750)(-8700 3700);
WIRE 16 -1 (-8700 3750)(-8525 3750);
WIRE 16 -1 (-8700 3800)(-8700 3750);
WIRE 16 -1 (-8700 3850)(-8700 3800);
WIRE 16 -1 (-8700 3800)(-8525 3800);
WIRE 16 -1 (-8525 3850)(-8700 3850);
WIRE 16 -1 (-8700 3900)(-8700 3850);
WIRE 16 -1 (-8700 3900)(-8525 3900);
WIRE 16 -1 (-8700 3950)(-8700 3900);
WIRE 16 -1 (-8700 3950)(-8525 3950);
WIRE 16 -1 (-8700 4000)(-8700 3950);
WIRE 16 -1 (-8700 4000)(-8525 4000);
WIRE 16 -1 (-8700 4050)(-8700 4000);
WIRE 16 -1 (-8700 4100)(-8700 4050);
WIRE 16 -1 (-8700 4050)(-8525 4050);
WIRE 16 -1 (-8525 4100)(-8700 4100);
WIRE 16 -1 (-8700 4150)(-8700 4100);
WIRE 16 -1 (-8700 4150)(-8525 4150);
WIRE 16 -1 (-8700 4200)(-8700 4150);
WIRE 16 -1 (-8700 4200)(-8525 4200);
WIRE 16 -1 (-8700 4250)(-8700 4200);
WIRE 16 -1 (-8700 4250)(-8525 4250);
WIRE 16 -1 (-8700 4300)(-8700 4250);
WIRE 16 -1 (-8700 4300)(-8525 4300);
WIRE 16 -1 (-8700 4350)(-8700 4300);
WIRE 16 -1 (-8700 4400)(-8700 4350);
WIRE 16 -1 (-8700 4350)(-8525 4350);
WIRE 16 -1 (-8525 4400)(-8700 4400);
WIRE 16 -1 (-8700 4450)(-8700 4400);
WIRE 16 -1 (-8700 4450)(-8525 4450);
WIRE 16 -1 (-8700 4500)(-8700 4450);
WIRE 16 -1 (-8700 4500)(-8525 4500);
WIRE 16 -1 (-8700 4550)(-8700 4500);
WIRE 16 -1 (-8700 4550)(-8525 4550);
WIRE 16 -1 (-8700 4600)(-8700 4550);
WIRE 16 -1 (-8700 4650)(-8700 4600);
WIRE 16 -1 (-8700 4600)(-8525 4600);
WIRE 16 -1 (-8525 4650)(-8700 4650);
WIRE 16 -1 (-8700 4700)(-8700 4650);
WIRE 16 -1 (-8700 4700)(-8525 4700);
WIRE 16 -1 (-8700 4750)(-8700 4700);
WIRE 16 -1 (-8700 4750)(-8525 4750);
WIRE 16 -1 (-8700 4800)(-8700 4750);
WIRE 16 -1 (-8700 4800)(-8525 4800);
WIRE 16 -1 (-8700 4850)(-8700 4800);
WIRE 16 -1 (-8700 4900)(-8700 4850);
WIRE 16 -1 (-8700 4850)(-8525 4850);
WIRE 16 -1 (-8525 4900)(-8700 4900);
WIRE 16 -1 (-8700 4950)(-8700 4900);
WIRE 16 -1 (-8700 4950)(-8525 4950);
WIRE 16 -1 (-8700 5000)(-8700 4950);
WIRE 16 -1 (-8700 5000)(-8525 5000);
WIRE 16 -1 (-8700 5050)(-8700 5000);
WIRE 16 -1 (-8700 5050)(-8525 5050);
WIRE 16 -1 (-8700 5100)(-8700 5050);
WIRE 16 -1 (-8700 5150)(-8700 5100);
WIRE 16 -1 (-8700 5100)(-8525 5100);
WIRE 16 -1 (-8525 5150)(-8700 5150);
WIRE 16 -1 (-8700 5200)(-8700 5150);
WIRE 16 -1 (-8700 5200)(-8525 5200);
WIRE 16 -1 (-8700 5250)(-8700 5200);
WIRE 16 -1 (-8700 5250)(-8525 5250);
WIRE 16 -1 (-8700 5300)(-8700 5250);
WIRE 16 -1 (-8700 5300)(-8525 5300);
WIRE 16 -1 (-8700 5350)(-8700 5300);
WIRE 16 -1 (-8700 5400)(-8700 5350);
WIRE 16 -1 (-8700 5350)(-8525 5350);
WIRE 16 -1 (-8525 5400)(-8700 5400);
WIRE 16 -1 (-8700 5450)(-8700 5400);
WIRE 16 -1 (-8700 5450)(-8525 5450);
WIRE 16 -1 (-8700 5500)(-8700 5450);
WIRE 16 -1 (-8700 5500)(-8525 5500);
WIRE 16 -1 (-8700 5550)(-8700 5500);
WIRE 16 -1 (-8700 5550)(-8525 5550);
WIRE 16 -1 (-8700 5600)(-8700 5550);
WIRE 16 -1 (-8700 5650)(-8700 5600);
WIRE 16 -1 (-8700 5600)(-8525 5600);
WIRE 16 -1 (-8525 5650)(-8700 5650);
WIRE 16 -1 (-8700 5700)(-8700 5650);
WIRE 16 -1 (-8700 5700)(-8525 5700);
WIRE 16 -1 (-8700 5750)(-8700 5700);
WIRE 16 -1 (-8700 5750)(-8525 5750);
WIRE 16 -1 (-8700 5800)(-8700 5750);
WIRE 16 -1 (-8700 5800)(-8525 5800);
WIRE 16 -1 (-8700 5850)(-8700 5800);
WIRE 16 -1 (-8700 5900)(-8700 5850);
WIRE 16 -1 (-8700 5850)(-8525 5850);
WIRE 16 -1 (-8525 5900)(-8700 5900);
WIRE 16 -1 (-8700 5950)(-8700 5900);
WIRE 16 -1 (-8700 5950)(-8525 5950);
WIRE 16 -1 (-8700 6000)(-8700 5950);
WIRE 16 -1 (-8700 6000)(-8525 6000);
WIRE 16 -1 (-8700 6050)(-8700 6000);
WIRE 16 -1 (-8700 6050)(-8525 6050);
WIRE 16 -1 (-8700 6100)(-8700 6050);
WIRE 16 -1 (-8700 6150)(-8700 6100);
WIRE 16 -1 (-8700 6100)(-8525 6100);
WIRE 16 -1 (-8525 6150)(-8700 6150);
WIRE 16 -1 (-8700 6200)(-8700 6150);
WIRE 16 -1 (-8700 6200)(-8525 6200);
WIRE 16 -1 (-8700 6250)(-8700 6200);
WIRE 16 -1 (-8700 6250)(-8525 6250);
WIRE 16 -1 (-8700 6300)(-8700 6250);
WIRE 16 -1 (-8700 6300)(-8525 6300);
WIRE 16 -1 (-8700 6350)(-8700 6300);
WIRE 16 -1 (-8700 6400)(-8700 6350);
WIRE 16 -1 (-8700 6350)(-8525 6350);
WIRE 16 -1 (-8525 6400)(-8700 6400);
WIRE 16 -1 (-8700 6450)(-8700 6400);
WIRE 16 -1 (-8700 6450)(-8525 6450);
WIRE 16 -1 (-7425 600)(-7250 600);
WIRE 16 -1 (-7250 650)(-7250 600);
WIRE 16 -1 (-7250 525)(-7250 600);
WIRE 16 -1 (-7425 650)(-7250 650);
WIRE 16 -1 (-7250 700)(-7250 650);
WIRE 16 -1 (-7425 700)(-7250 700);
WIRE 16 -1 (-7250 750)(-7250 700);
WIRE 16 -1 (-7425 750)(-7250 750);
WIRE 16 -1 (-7250 800)(-7250 750);
WIRE 16 -1 (-7425 800)(-7250 800);
WIRE 16 -1 (-7250 850)(-7250 800);
WIRE 16 -1 (-7425 850)(-7250 850);
WIRE 16 -1 (-7250 900)(-7250 850);
WIRE 16 -1 (-7425 900)(-7250 900);
WIRE 16 -1 (-7250 950)(-7250 900);
WIRE 16 -1 (-7425 950)(-7250 950);
WIRE 16 -1 (-7250 1000)(-7250 950);
WIRE 16 -1 (-7425 1000)(-7250 1000);
WIRE 16 -1 (-7250 1050)(-7250 1000);
WIRE 16 -1 (-7250 1100)(-7250 1050);
WIRE 16 -1 (-7425 1050)(-7250 1050);
WIRE 16 -1 (-7425 1100)(-7250 1100);
WIRE 16 -1 (-7250 1150)(-7250 1100);
WIRE 16 -1 (-7425 1150)(-7250 1150);
WIRE 16 -1 (-7250 1200)(-7250 1150);
WIRE 16 -1 (-7425 1200)(-7250 1200);
WIRE 16 -1 (-7250 1250)(-7250 1200);
WIRE 16 -1 (-7425 1250)(-7250 1250);
WIRE 16 -1 (-7250 1300)(-7250 1250);
WIRE 16 -1 (-7425 1300)(-7250 1300);
WIRE 16 -1 (-7250 1350)(-7250 1300);
WIRE 16 -1 (-7425 1350)(-7250 1350);
WIRE 16 -1 (-7250 1400)(-7250 1350);
WIRE 16 -1 (-7425 1400)(-7250 1400);
WIRE 16 -1 (-7250 1450)(-7250 1400);
WIRE 16 -1 (-7425 1450)(-7250 1450);
WIRE 16 -1 (-7250 1500)(-7250 1450);
WIRE 16 -1 (-7425 1500)(-7250 1500);
WIRE 16 -1 (-7250 1550)(-7250 1500);
WIRE 16 -1 (-7250 1600)(-7250 1550);
WIRE 16 -1 (-7425 1550)(-7250 1550);
WIRE 16 -1 (-7425 1600)(-7250 1600);
WIRE 16 -1 (-7250 1650)(-7250 1600);
WIRE 16 -1 (-7425 1650)(-7250 1650);
WIRE 16 -1 (-7250 1700)(-7250 1650);
WIRE 16 -1 (-7425 1700)(-7250 1700);
WIRE 16 -1 (-7250 1750)(-7250 1700);
WIRE 16 -1 (-7425 1750)(-7250 1750);
WIRE 16 -1 (-7250 1800)(-7250 1750);
WIRE 16 -1 (-7425 1800)(-7250 1800);
WIRE 16 -1 (-7250 1850)(-7250 1800);
WIRE 16 -1 (-7425 1850)(-7250 1850);
WIRE 16 -1 (-7250 1900)(-7250 1850);
WIRE 16 -1 (-7425 1900)(-7250 1900);
WIRE 16 -1 (-7250 1950)(-7250 1900);
WIRE 16 -1 (-7425 1950)(-7250 1950);
WIRE 16 -1 (-7250 2000)(-7250 1950);
WIRE 16 -1 (-7425 2000)(-7250 2000);
WIRE 16 -1 (-7250 2050)(-7250 2000);
WIRE 16 -1 (-7250 2100)(-7250 2050);
WIRE 16 -1 (-7425 2050)(-7250 2050);
WIRE 16 -1 (-7425 2100)(-7250 2100);
WIRE 16 -1 (-7250 2150)(-7250 2100);
WIRE 16 -1 (-7425 2150)(-7250 2150);
WIRE 16 -1 (-7250 2200)(-7250 2150);
WIRE 16 -1 (-7425 2200)(-7250 2200);
WIRE 16 -1 (-7250 2250)(-7250 2200);
WIRE 16 -1 (-7425 2250)(-7250 2250);
WIRE 16 -1 (-7250 2300)(-7250 2250);
WIRE 16 -1 (-7425 2300)(-7250 2300);
WIRE 16 -1 (-7250 2350)(-7250 2300);
WIRE 16 -1 (-7425 2350)(-7250 2350);
WIRE 16 -1 (-7250 2400)(-7250 2350);
WIRE 16 -1 (-7425 2400)(-7250 2400);
WIRE 16 -1 (-7250 2450)(-7250 2400);
WIRE 16 -1 (-7425 2450)(-7250 2450);
WIRE 16 -1 (-7250 2500)(-7250 2450);
WIRE 16 -1 (-7425 2500)(-7250 2500);
WIRE 16 -1 (-7250 2550)(-7250 2500);
WIRE 16 -1 (-7425 2550)(-7250 2550);
WIRE 16 -1 (-7250 2600)(-7250 2550);
WIRE 16 -1 (-7250 2650)(-7250 2600);
WIRE 16 -1 (-7425 2600)(-7250 2600);
WIRE 16 -1 (-7425 2650)(-7250 2650);
WIRE 16 -1 (-7250 2700)(-7250 2650);
WIRE 16 -1 (-7425 2700)(-7250 2700);
WIRE 16 -1 (-7250 2750)(-7250 2700);
WIRE 16 -1 (-7425 2750)(-7250 2750);
WIRE 16 -1 (-7250 2800)(-7250 2750);
WIRE 16 -1 (-7425 2800)(-7250 2800);
WIRE 16 -1 (-7250 2850)(-7250 2800);
WIRE 16 -1 (-7425 2850)(-7250 2850);
WIRE 16 -1 (-7250 2900)(-7250 2850);
WIRE 16 -1 (-7425 2900)(-7250 2900);
WIRE 16 -1 (-7250 2950)(-7250 2900);
WIRE 16 -1 (-7425 2950)(-7250 2950);
WIRE 16 -1 (-7250 3000)(-7250 2950);
WIRE 16 -1 (-7425 3000)(-7250 3000);
WIRE 16 -1 (-7250 3050)(-7250 3000);
WIRE 16 -1 (-7425 3050)(-7250 3050);
WIRE 16 -1 (-7250 3100)(-7250 3050);
WIRE 16 -1 (-7250 3150)(-7250 3100);
WIRE 16 -1 (-7425 3100)(-7250 3100);
WIRE 16 -1 (-7425 3150)(-7250 3150);
WIRE 16 -1 (-7250 3200)(-7250 3150);
WIRE 16 -1 (-7425 3200)(-7250 3200);
WIRE 16 -1 (-7250 3250)(-7250 3200);
WIRE 16 -1 (-7425 3250)(-7250 3250);
WIRE 16 -1 (-7250 3300)(-7250 3250);
WIRE 16 -1 (-7425 3300)(-7250 3300);
WIRE 16 -1 (-7250 3350)(-7250 3300);
WIRE 16 -1 (-7425 3350)(-7250 3350);
WIRE 16 -1 (-7250 3400)(-7250 3350);
WIRE 16 -1 (-7425 3400)(-7250 3400);
WIRE 16 -1 (-7250 3450)(-7250 3400);
WIRE 16 -1 (-7425 3450)(-7250 3450);
WIRE 16 -1 (-7250 3500)(-7250 3450);
WIRE 16 -1 (-7425 3500)(-7250 3500);
WIRE 16 -1 (-7250 3550)(-7250 3500);
WIRE 16 -1 (-7425 3550)(-7250 3550);
WIRE 16 -1 (-7250 3600)(-7250 3550);
WIRE 16 -1 (-7250 3650)(-7250 3600);
WIRE 16 -1 (-7425 3600)(-7250 3600);
WIRE 16 -1 (-7425 3650)(-7250 3650);
WIRE 16 -1 (-7250 3700)(-7250 3650);
WIRE 16 -1 (-7425 3700)(-7250 3700);
WIRE 16 -1 (-7250 3750)(-7250 3700);
WIRE 16 -1 (-7425 3750)(-7250 3750);
WIRE 16 -1 (-7250 3800)(-7250 3750);
WIRE 16 -1 (-7425 3800)(-7250 3800);
WIRE 16 -1 (-7250 3850)(-7250 3800);
WIRE 16 -1 (-7425 3850)(-7250 3850);
WIRE 16 -1 (-7250 3900)(-7250 3850);
WIRE 16 -1 (-7425 3900)(-7250 3900);
WIRE 16 -1 (-7250 3950)(-7250 3900);
WIRE 16 -1 (-7425 3950)(-7250 3950);
WIRE 16 -1 (-7250 4000)(-7250 3950);
WIRE 16 -1 (-7425 4000)(-7250 4000);
WIRE 16 -1 (-7250 4050)(-7250 4000);
WIRE 16 -1 (-7425 4050)(-7250 4050);
WIRE 16 -1 (-7250 4100)(-7250 4050);
WIRE 16 -1 (-7250 4150)(-7250 4100);
WIRE 16 -1 (-7425 4100)(-7250 4100);
WIRE 16 -1 (-7425 4150)(-7250 4150);
WIRE 16 -1 (-7250 4200)(-7250 4150);
WIRE 16 -1 (-7425 4200)(-7250 4200);
WIRE 16 -1 (-7250 4250)(-7250 4200);
WIRE 16 -1 (-7425 4250)(-7250 4250);
WIRE 16 -1 (-7250 4300)(-7250 4250);
WIRE 16 -1 (-7425 4300)(-7250 4300);
WIRE 16 -1 (-7250 4350)(-7250 4300);
WIRE 16 -1 (-7425 4350)(-7250 4350);
WIRE 16 -1 (-7250 4400)(-7250 4350);
WIRE 16 -1 (-7425 4400)(-7250 4400);
WIRE 16 -1 (-7250 4450)(-7250 4400);
WIRE 16 -1 (-7425 4450)(-7250 4450);
WIRE 16 -1 (-7250 4500)(-7250 4450);
WIRE 16 -1 (-7425 4500)(-7250 4500);
WIRE 16 -1 (-7250 4550)(-7250 4500);
WIRE 16 -1 (-7425 4550)(-7250 4550);
WIRE 16 -1 (-7250 4600)(-7250 4550);
WIRE 16 -1 (-7425 4600)(-7250 4600);
WIRE 16 -1 (-7250 4650)(-7250 4600);
WIRE 16 -1 (-7250 4700)(-7250 4650);
WIRE 16 -1 (-7425 4650)(-7250 4650);
WIRE 16 -1 (-7425 4700)(-7250 4700);
WIRE 16 -1 (-7250 4750)(-7250 4700);
WIRE 16 -1 (-7425 4750)(-7250 4750);
WIRE 16 -1 (-7250 4800)(-7250 4750);
WIRE 16 -1 (-7425 4800)(-7250 4800);
WIRE 16 -1 (-7250 4850)(-7250 4800);
WIRE 16 -1 (-7425 4850)(-7250 4850);
WIRE 16 -1 (-7250 4900)(-7250 4850);
WIRE 16 -1 (-7425 4900)(-7250 4900);
WIRE 16 -1 (-7250 4950)(-7250 4900);
WIRE 16 -1 (-7425 4950)(-7250 4950);
WIRE 16 -1 (-7250 5000)(-7250 4950);
WIRE 16 -1 (-7425 5000)(-7250 5000);
WIRE 16 -1 (-7250 5050)(-7250 5000);
WIRE 16 -1 (-7425 5050)(-7250 5050);
WIRE 16 -1 (-7250 5100)(-7250 5050);
WIRE 16 -1 (-7425 5100)(-7250 5100);
WIRE 16 -1 (-7250 5150)(-7250 5100);
WIRE 16 -1 (-7250 5200)(-7250 5150);
WIRE 16 -1 (-7425 5150)(-7250 5150);
WIRE 16 -1 (-7425 5200)(-7250 5200);
WIRE 16 -1 (-7250 5250)(-7250 5200);
WIRE 16 -1 (-7425 5250)(-7250 5250);
WIRE 16 -1 (-7250 5300)(-7250 5250);
WIRE 16 -1 (-7425 5300)(-7250 5300);
WIRE 16 -1 (-7250 5350)(-7250 5300);
WIRE 16 -1 (-7425 5350)(-7250 5350);
WIRE 16 -1 (-7250 5400)(-7250 5350);
WIRE 16 -1 (-7425 5400)(-7250 5400);
WIRE 16 -1 (-7250 5450)(-7250 5400);
WIRE 16 -1 (-7425 5450)(-7250 5450);
WIRE 16 -1 (-7250 5500)(-7250 5450);
WIRE 16 -1 (-7425 5500)(-7250 5500);
WIRE 16 -1 (-7250 5550)(-7250 5500);
WIRE 16 -1 (-7425 5550)(-7250 5550);
WIRE 16 -1 (-7250 5600)(-7250 5550);
WIRE 16 -1 (-7425 5600)(-7250 5600);
WIRE 16 -1 (-7250 5650)(-7250 5600);
WIRE 16 -1 (-7250 5700)(-7250 5650);
WIRE 16 -1 (-7425 5650)(-7250 5650);
WIRE 16 -1 (-7425 5700)(-7250 5700);
WIRE 16 -1 (-7250 5750)(-7250 5700);
WIRE 16 -1 (-7425 5750)(-7250 5750);
WIRE 16 -1 (-7250 5800)(-7250 5750);
WIRE 16 -1 (-7425 5800)(-7250 5800);
WIRE 16 -1 (-7250 5850)(-7250 5800);
WIRE 16 -1 (-7425 5850)(-7250 5850);
WIRE 16 -1 (-7250 5900)(-7250 5850);
WIRE 16 -1 (-7425 5900)(-7250 5900);
WIRE 16 -1 (-7250 5950)(-7250 5900);
WIRE 16 -1 (-7425 5950)(-7250 5950);
WIRE 16 -1 (-7250 6000)(-7250 5950);
WIRE 16 -1 (-7425 6000)(-7250 6000);
WIRE 16 -1 (-7250 6050)(-7250 6000);
WIRE 16 -1 (-7425 6050)(-7250 6050);
WIRE 16 -1 (-7250 6100)(-7250 6050);
WIRE 16 -1 (-7425 6100)(-7250 6100);
WIRE 16 -1 (-7250 6150)(-7250 6100);
WIRE 16 -1 (-7250 6200)(-7250 6150);
WIRE 16 -1 (-7425 6150)(-7250 6150);
WIRE 16 -1 (-7425 6200)(-7250 6200);
WIRE 16 -1 (-7250 6250)(-7250 6200);
WIRE 16 -1 (-7425 6250)(-7250 6250);
WIRE 16 -1 (-7250 6300)(-7250 6250);
WIRE 16 -1 (-7425 6300)(-7250 6300);
WIRE 16 -1 (-7250 6350)(-7250 6300);
WIRE 16 -1 (-7425 6350)(-7250 6350);
WIRE 16 -1 (-7250 6400)(-7250 6350);
WIRE 16 -1 (-7425 6400)(-7250 6400);
WIRE 16 -1 (-7250 6450)(-7250 6400);
WIRE 16 -1 (-7425 6450)(-7250 6450);
WIRE 16 -1 (-6675 525)(-6675 550);
WIRE 16 -1 (-6675 550)(-6500 550);
WIRE 16 -1 (-6675 600)(-6675 550);
WIRE 16 -1 (-6675 600)(-6500 600);
WIRE 16 -1 (-6675 650)(-6675 600);
WIRE 16 -1 (-6675 650)(-6500 650);
WIRE 16 -1 (-6675 700)(-6675 650);
WIRE 16 -1 (-6675 700)(-6500 700);
WIRE 16 -1 (-6675 750)(-6675 700);
WIRE 16 -1 (-6500 750)(-6675 750);
WIRE 16 -1 (-6675 800)(-6675 750);
WIRE 16 -1 (-6675 800)(-6500 800);
WIRE 16 -1 (-6675 850)(-6675 800);
WIRE 16 -1 (-6675 850)(-6500 850);
WIRE 16 -1 (-6675 900)(-6675 850);
WIRE 16 -1 (-6675 900)(-6500 900);
WIRE 16 -1 (-6675 950)(-6675 900);
WIRE 16 -1 (-6675 950)(-6500 950);
WIRE 16 -1 (-6675 1000)(-6675 950);
WIRE 16 -1 (-6675 1050)(-6675 1000);
WIRE 16 -1 (-6500 1000)(-6675 1000);
WIRE 16 -1 (-6675 1050)(-6500 1050);
WIRE 16 -1 (-6675 1100)(-6675 1050);
WIRE 16 -1 (-6675 1100)(-6500 1100);
WIRE 16 -1 (-6675 1150)(-6675 1100);
WIRE 16 -1 (-6675 1150)(-6500 1150);
WIRE 16 -1 (-6675 1200)(-6675 1150);
WIRE 16 -1 (-6675 1200)(-6500 1200);
WIRE 16 -1 (-6675 1250)(-6675 1200);
WIRE 16 -1 (-6500 1250)(-6675 1250);
WIRE 16 -1 (-6675 1300)(-6675 1250);
WIRE 16 -1 (-6675 1300)(-6500 1300);
WIRE 16 -1 (-6675 1350)(-6675 1300);
WIRE 16 -1 (-6675 1350)(-6500 1350);
WIRE 16 -1 (-6675 1400)(-6675 1350);
WIRE 16 -1 (-6675 1400)(-6500 1400);
WIRE 16 -1 (-6675 1450)(-6675 1400);
WIRE 16 -1 (-6675 1450)(-6500 1450);
WIRE 16 -1 (-6675 1500)(-6675 1450);
WIRE 16 -1 (-6500 1500)(-6675 1500);
WIRE 16 -1 (-6675 1550)(-6675 1500);
WIRE 16 -1 (-6675 1550)(-6500 1550);
WIRE 16 -1 (-6675 1600)(-6675 1550);
WIRE 16 -1 (-6675 1600)(-6500 1600);
WIRE 16 -1 (-6675 1650)(-6675 1600);
WIRE 16 -1 (-6675 1650)(-6500 1650);
WIRE 16 -1 (-6675 1700)(-6675 1650);
WIRE 16 -1 (-6675 1700)(-6500 1700);
WIRE 16 -1 (-6675 1750)(-6675 1700);
WIRE 16 -1 (-6500 1750)(-6675 1750);
WIRE 16 -1 (-6675 1800)(-6675 1750);
WIRE 16 -1 (-6675 1800)(-6500 1800);
WIRE 16 -1 (-6675 1850)(-6675 1800);
WIRE 16 -1 (-6675 1850)(-6500 1850);
WIRE 16 -1 (-6675 1900)(-6675 1850);
WIRE 16 -1 (-6675 1900)(-6500 1900);
WIRE 16 -1 (-6675 1950)(-6675 1900);
WIRE 16 -1 (-6675 1950)(-6500 1950);
WIRE 16 -1 (-6675 2000)(-6675 1950);
WIRE 16 -1 (-6675 2050)(-6675 2000);
WIRE 16 -1 (-6500 2000)(-6675 2000);
WIRE 16 -1 (-6675 2050)(-6500 2050);
WIRE 16 -1 (-6675 2100)(-6675 2050);
WIRE 16 -1 (-6675 2100)(-6500 2100);
WIRE 16 -1 (-6675 2150)(-6675 2100);
WIRE 16 -1 (-6675 2150)(-6500 2150);
WIRE 16 -1 (-6675 2200)(-6675 2150);
WIRE 16 -1 (-6675 2200)(-6500 2200);
WIRE 16 -1 (-6675 2250)(-6675 2200);
WIRE 16 -1 (-6675 2250)(-6500 2250);
WIRE 16 -1 (-6675 2300)(-6675 2250);
WIRE 16 -1 (-6500 2300)(-6675 2300);
WIRE 16 -1 (-6675 2350)(-6675 2300);
WIRE 16 -1 (-6675 2350)(-6500 2350);
WIRE 16 -1 (-6675 2400)(-6675 2350);
WIRE 16 -1 (-6675 2400)(-6500 2400);
WIRE 16 -1 (-6675 2450)(-6675 2400);
WIRE 16 -1 (-6675 2450)(-6500 2450);
WIRE 16 -1 (-6675 2500)(-6675 2450);
WIRE 16 -1 (-6675 2500)(-6500 2500);
WIRE 16 -1 (-6675 2550)(-6675 2500);
WIRE 16 -1 (-6500 2550)(-6675 2550);
WIRE 16 -1 (-6675 2600)(-6675 2550);
WIRE 16 -1 (-6675 2600)(-6500 2600);
WIRE 16 -1 (-6675 2650)(-6675 2600);
WIRE 16 -1 (-6675 2650)(-6500 2650);
WIRE 16 -1 (-6675 2700)(-6675 2650);
WIRE 16 -1 (-6675 2700)(-6500 2700);
WIRE 16 -1 (-6675 2750)(-6675 2700);
WIRE 16 -1 (-6675 2750)(-6500 2750);
WIRE 16 -1 (-6675 2800)(-6675 2750);
WIRE 16 -1 (-6500 2800)(-6675 2800);
WIRE 16 -1 (-6675 2850)(-6675 2800);
WIRE 16 -1 (-6675 2850)(-6500 2850);
WIRE 16 -1 (-6675 2900)(-6675 2850);
WIRE 16 -1 (-6675 2900)(-6500 2900);
WIRE 16 -1 (-6675 2950)(-6675 2900);
WIRE 16 -1 (-6675 2950)(-6500 2950);
WIRE 16 -1 (-6675 3000)(-6675 2950);
WIRE 16 -1 (-6675 3000)(-6500 3000);
WIRE 16 -1 (-6675 3050)(-6675 3000);
WIRE 16 -1 (-6675 3100)(-6675 3050);
WIRE 16 -1 (-6500 3050)(-6675 3050);
WIRE 16 -1 (-6675 3100)(-6500 3100);
WIRE 16 -1 (-6675 3150)(-6675 3100);
WIRE 16 -1 (-6675 3150)(-6500 3150);
WIRE 16 -1 (-6675 3200)(-6675 3150);
WIRE 16 -1 (-6675 3200)(-6500 3200);
WIRE 16 -1 (-6675 3250)(-6675 3200);
WIRE 16 -1 (-6675 3250)(-6500 3250);
WIRE 16 -1 (-6675 3300)(-6675 3250);
WIRE 16 -1 (-6500 3300)(-6675 3300);
WIRE 16 -1 (-6675 3350)(-6675 3300);
WIRE 16 -1 (-6675 3350)(-6500 3350);
WIRE 16 -1 (-6675 3400)(-6675 3350);
WIRE 16 -1 (-6675 3400)(-6500 3400);
WIRE 16 -1 (-6675 3450)(-6675 3400);
WIRE 16 -1 (-6675 3450)(-6500 3450);
WIRE 16 -1 (-6675 3500)(-6675 3450);
WIRE 16 -1 (-6675 3500)(-6500 3500);
WIRE 16 -1 (-6675 3550)(-6675 3500);
WIRE 16 -1 (-6500 3550)(-6675 3550);
WIRE 16 -1 (-6675 3600)(-6675 3550);
WIRE 16 -1 (-6675 3600)(-6500 3600);
WIRE 16 -1 (-6675 3650)(-6675 3600);
WIRE 16 -1 (-6675 3650)(-6500 3650);
WIRE 16 -1 (-6675 3700)(-6675 3650);
WIRE 16 -1 (-6675 3700)(-6500 3700);
WIRE 16 -1 (-6675 3750)(-6675 3700);
WIRE 16 -1 (-6675 3750)(-6500 3750);
WIRE 16 -1 (-6675 3800)(-6675 3750);
WIRE 16 -1 (-6500 3800)(-6675 3800);
WIRE 16 -1 (-6675 3850)(-6675 3800);
WIRE 16 -1 (-6675 3850)(-6500 3850);
WIRE 16 -1 (-6675 3900)(-6675 3850);
WIRE 16 -1 (-6675 3900)(-6500 3900);
WIRE 16 -1 (-6675 3950)(-6675 3900);
WIRE 16 -1 (-6675 3950)(-6500 3950);
WIRE 16 -1 (-6675 4000)(-6675 3950);
WIRE 16 -1 (-6675 4000)(-6500 4000);
WIRE 16 -1 (-6675 4050)(-6675 4000);
WIRE 16 -1 (-6675 4100)(-6675 4050);
WIRE 16 -1 (-6500 4050)(-6675 4050);
WIRE 16 -1 (-6675 4100)(-6500 4100);
WIRE 16 -1 (-6675 4150)(-6675 4100);
WIRE 16 -1 (-6675 4150)(-6500 4150);
WIRE 16 -1 (-6675 4200)(-6675 4150);
WIRE 16 -1 (-6675 4200)(-6500 4200);
WIRE 16 -1 (-6675 4250)(-6675 4200);
WIRE 16 -1 (-6675 4250)(-6500 4250);
WIRE 16 -1 (-6675 4300)(-6675 4250);
WIRE 16 -1 (-6675 4300)(-6500 4300);
WIRE 16 -1 (-6675 4350)(-6675 4300);
WIRE 16 -1 (-6500 4350)(-6675 4350);
WIRE 16 -1 (-6675 4400)(-6675 4350);
WIRE 16 -1 (-6675 4400)(-6500 4400);
WIRE 16 -1 (-6675 4450)(-6675 4400);
WIRE 16 -1 (-6675 4450)(-6500 4450);
WIRE 16 -1 (-6675 4500)(-6675 4450);
WIRE 16 -1 (-6675 4500)(-6500 4500);
WIRE 16 -1 (-6675 4550)(-6675 4500);
WIRE 16 -1 (-6675 4550)(-6500 4550);
WIRE 16 -1 (-6675 4600)(-6675 4550);
WIRE 16 -1 (-6500 4600)(-6675 4600);
WIRE 16 -1 (-6675 4650)(-6675 4600);
WIRE 16 -1 (-6675 4650)(-6500 4650);
WIRE 16 -1 (-6675 4700)(-6675 4650);
WIRE 16 -1 (-6675 4700)(-6500 4700);
WIRE 16 -1 (-6675 4750)(-6675 4700);
WIRE 16 -1 (-6675 4750)(-6500 4750);
WIRE 16 -1 (-6675 4800)(-6675 4750);
WIRE 16 -1 (-6675 4800)(-6500 4800);
WIRE 16 -1 (-6675 4850)(-6675 4800);
WIRE 16 -1 (-6500 4850)(-6675 4850);
WIRE 16 -1 (-6675 4900)(-6675 4850);
WIRE 16 -1 (-6675 4900)(-6500 4900);
WIRE 16 -1 (-6675 4950)(-6675 4900);
WIRE 16 -1 (-6675 4950)(-6500 4950);
WIRE 16 -1 (-6675 5000)(-6675 4950);
WIRE 16 -1 (-6675 5000)(-6500 5000);
WIRE 16 -1 (-6675 5050)(-6675 5000);
WIRE 16 -1 (-6675 5050)(-6500 5050);
WIRE 16 -1 (-6675 5100)(-6675 5050);
WIRE 16 -1 (-6675 5150)(-6675 5100);
WIRE 16 -1 (-6500 5100)(-6675 5100);
WIRE 16 -1 (-6675 5150)(-6500 5150);
WIRE 16 -1 (-6675 5200)(-6675 5150);
WIRE 16 -1 (-6675 5200)(-6500 5200);
WIRE 16 -1 (-6675 5250)(-6675 5200);
WIRE 16 -1 (-6675 5250)(-6500 5250);
WIRE 16 -1 (-6675 5300)(-6675 5250);
WIRE 16 -1 (-6675 5300)(-6500 5300);
WIRE 16 -1 (-6675 5350)(-6675 5300);
WIRE 16 -1 (-6500 5350)(-6675 5350);
WIRE 16 -1 (-6675 5400)(-6675 5350);
WIRE 16 -1 (-6675 5400)(-6500 5400);
WIRE 16 -1 (-6675 5450)(-6675 5400);
WIRE 16 -1 (-6675 5450)(-6500 5450);
WIRE 16 -1 (-6675 5500)(-6675 5450);
WIRE 16 -1 (-6675 5500)(-6500 5500);
WIRE 16 -1 (-6675 5550)(-6675 5500);
WIRE 16 -1 (-6675 5550)(-6500 5550);
WIRE 16 -1 (-6675 5600)(-6675 5550);
WIRE 16 -1 (-6500 5600)(-6675 5600);
WIRE 16 -1 (-6675 5650)(-6675 5600);
WIRE 16 -1 (-6675 5650)(-6500 5650);
WIRE 16 -1 (-6675 5700)(-6675 5650);
WIRE 16 -1 (-6675 5700)(-6500 5700);
WIRE 16 -1 (-6675 5750)(-6675 5700);
WIRE 16 -1 (-6675 5750)(-6500 5750);
WIRE 16 -1 (-6675 5800)(-6675 5750);
WIRE 16 -1 (-6675 5800)(-6500 5800);
WIRE 16 -1 (-6675 5850)(-6675 5800);
WIRE 16 -1 (-6500 5850)(-6675 5850);
WIRE 16 -1 (-6675 5900)(-6675 5850);
WIRE 16 -1 (-6675 5900)(-6500 5900);
WIRE 16 -1 (-6675 5950)(-6675 5900);
WIRE 16 -1 (-6675 5950)(-6500 5950);
WIRE 16 -1 (-6675 6000)(-6675 5950);
WIRE 16 -1 (-6675 6000)(-6500 6000);
WIRE 16 -1 (-6675 6050)(-6675 6000);
WIRE 16 -1 (-6675 6050)(-6500 6050);
WIRE 16 -1 (-6675 6100)(-6675 6050);
WIRE 16 -1 (-6675 6150)(-6675 6100);
WIRE 16 -1 (-6500 6100)(-6675 6100);
WIRE 16 -1 (-6675 6150)(-6500 6150);
WIRE 16 -1 (-6675 6200)(-6675 6150);
WIRE 16 -1 (-6675 6200)(-6500 6200);
WIRE 16 -1 (-6675 6250)(-6675 6200);
WIRE 16 -1 (-6675 6250)(-6500 6250);
WIRE 16 -1 (-6675 6300)(-6675 6250);
WIRE 16 -1 (-6675 6300)(-6500 6300);
WIRE 16 -1 (-6675 6350)(-6675 6300);
WIRE 16 -1 (-6500 6350)(-6675 6350);
WIRE 16 -1 (-6675 6400)(-6675 6350);
WIRE 16 -1 (-6675 6400)(-6500 6400);
WIRE 16 -1 (-5225 600)(-5225 550);
WIRE 16 -1 (-5400 600)(-5225 600);
WIRE 16 -1 (-5225 650)(-5225 600);
WIRE 16 -1 (-5225 550)(-5225 525);
WIRE 16 -1 (-5400 550)(-5225 550);
WIRE 16 -1 (-5400 650)(-5225 650);
WIRE 16 -1 (-5225 700)(-5225 650);
WIRE 16 -1 (-5400 700)(-5225 700);
WIRE 16 -1 (-5225 750)(-5225 700);
WIRE 16 -1 (-5400 750)(-5225 750);
WIRE 16 -1 (-5225 800)(-5225 750);
WIRE 16 -1 (-5400 800)(-5225 800);
WIRE 16 -1 (-5225 850)(-5225 800);
WIRE 16 -1 (-5400 850)(-5225 850);
WIRE 16 -1 (-5225 900)(-5225 850);
WIRE 16 -1 (-5400 900)(-5225 900);
WIRE 16 -1 (-5225 950)(-5225 900);
WIRE 16 -1 (-5400 950)(-5225 950);
WIRE 16 -1 (-5225 1000)(-5225 950);
WIRE 16 -1 (-5400 1000)(-5225 1000);
WIRE 16 -1 (-5225 1050)(-5225 1000);
WIRE 16 -1 (-5225 1100)(-5225 1050);
WIRE 16 -1 (-5400 1050)(-5225 1050);
WIRE 16 -1 (-5400 1100)(-5225 1100);
WIRE 16 -1 (-5225 1150)(-5225 1100);
WIRE 16 -1 (-5400 1150)(-5225 1150);
WIRE 16 -1 (-5225 1200)(-5225 1150);
WIRE 16 -1 (-5400 1200)(-5225 1200);
WIRE 16 -1 (-5225 1250)(-5225 1200);
WIRE 16 -1 (-5400 1250)(-5225 1250);
WIRE 16 -1 (-5225 1300)(-5225 1250);
WIRE 16 -1 (-5400 1300)(-5225 1300);
WIRE 16 -1 (-5225 1350)(-5225 1300);
WIRE 16 -1 (-5400 1350)(-5225 1350);
WIRE 16 -1 (-5225 1400)(-5225 1350);
WIRE 16 -1 (-5400 1400)(-5225 1400);
WIRE 16 -1 (-5225 1450)(-5225 1400);
WIRE 16 -1 (-5400 1450)(-5225 1450);
WIRE 16 -1 (-5225 1500)(-5225 1450);
WIRE 16 -1 (-5400 1500)(-5225 1500);
WIRE 16 -1 (-5225 1550)(-5225 1500);
WIRE 16 -1 (-5225 1600)(-5225 1550);
WIRE 16 -1 (-5400 1550)(-5225 1550);
WIRE 16 -1 (-5400 1600)(-5225 1600);
WIRE 16 -1 (-5225 1650)(-5225 1600);
WIRE 16 -1 (-5400 1650)(-5225 1650);
WIRE 16 -1 (-5225 1700)(-5225 1650);
WIRE 16 -1 (-5400 1700)(-5225 1700);
WIRE 16 -1 (-5225 1750)(-5225 1700);
WIRE 16 -1 (-5400 1750)(-5225 1750);
WIRE 16 -1 (-5225 1800)(-5225 1750);
WIRE 16 -1 (-5400 1800)(-5225 1800);
WIRE 16 -1 (-5225 1850)(-5225 1800);
WIRE 16 -1 (-5400 1850)(-5225 1850);
WIRE 16 -1 (-5225 1900)(-5225 1850);
WIRE 16 -1 (-5400 1900)(-5225 1900);
WIRE 16 -1 (-5225 1950)(-5225 1900);
WIRE 16 -1 (-5400 1950)(-5225 1950);
WIRE 16 -1 (-5225 2000)(-5225 1950);
WIRE 16 -1 (-5400 2000)(-5225 2000);
WIRE 16 -1 (-5225 2050)(-5225 2000);
WIRE 16 -1 (-5225 2100)(-5225 2050);
WIRE 16 -1 (-5400 2050)(-5225 2050);
WIRE 16 -1 (-5400 2100)(-5225 2100);
WIRE 16 -1 (-5225 2150)(-5225 2100);
WIRE 16 -1 (-5400 2150)(-5225 2150);
WIRE 16 -1 (-5225 2200)(-5225 2150);
WIRE 16 -1 (-5400 2200)(-5225 2200);
WIRE 16 -1 (-5225 2250)(-5225 2200);
WIRE 16 -1 (-5400 2250)(-5225 2250);
WIRE 16 -1 (-5225 2300)(-5225 2250);
WIRE 16 -1 (-5400 2300)(-5225 2300);
WIRE 16 -1 (-5225 2350)(-5225 2300);
WIRE 16 -1 (-5400 2350)(-5225 2350);
WIRE 16 -1 (-5225 2400)(-5225 2350);
WIRE 16 -1 (-5400 2400)(-5225 2400);
WIRE 16 -1 (-5225 2450)(-5225 2400);
WIRE 16 -1 (-5400 2450)(-5225 2450);
WIRE 16 -1 (-5225 2500)(-5225 2450);
WIRE 16 -1 (-5400 2500)(-5225 2500);
WIRE 16 -1 (-5225 2550)(-5225 2500);
WIRE 16 -1 (-5400 2550)(-5225 2550);
WIRE 16 -1 (-5225 2600)(-5225 2550);
WIRE 16 -1 (-5225 2650)(-5225 2600);
WIRE 16 -1 (-5400 2600)(-5225 2600);
WIRE 16 -1 (-5400 2650)(-5225 2650);
WIRE 16 -1 (-5225 2700)(-5225 2650);
WIRE 16 -1 (-5400 2700)(-5225 2700);
WIRE 16 -1 (-5225 2750)(-5225 2700);
WIRE 16 -1 (-5400 2750)(-5225 2750);
WIRE 16 -1 (-5225 2800)(-5225 2750);
WIRE 16 -1 (-5400 2800)(-5225 2800);
WIRE 16 -1 (-5225 2850)(-5225 2800);
WIRE 16 -1 (-5400 2850)(-5225 2850);
WIRE 16 -1 (-5225 2900)(-5225 2850);
WIRE 16 -1 (-5400 2900)(-5225 2900);
WIRE 16 -1 (-5225 2950)(-5225 2900);
WIRE 16 -1 (-5400 2950)(-5225 2950);
WIRE 16 -1 (-5225 3000)(-5225 2950);
WIRE 16 -1 (-5400 3000)(-5225 3000);
WIRE 16 -1 (-5225 3050)(-5225 3000);
WIRE 16 -1 (-5400 3050)(-5225 3050);
WIRE 16 -1 (-5225 3100)(-5225 3050);
WIRE 16 -1 (-5225 3150)(-5225 3100);
WIRE 16 -1 (-5400 3100)(-5225 3100);
WIRE 16 -1 (-5400 3150)(-5225 3150);
WIRE 16 -1 (-5225 3200)(-5225 3150);
WIRE 16 -1 (-5400 3200)(-5225 3200);
WIRE 16 -1 (-5225 3250)(-5225 3200);
WIRE 16 -1 (-5400 3250)(-5225 3250);
WIRE 16 -1 (-5225 3300)(-5225 3250);
WIRE 16 -1 (-5400 3300)(-5225 3300);
WIRE 16 -1 (-5225 3350)(-5225 3300);
WIRE 16 -1 (-5400 3350)(-5225 3350);
WIRE 16 -1 (-5225 3400)(-5225 3350);
WIRE 16 -1 (-5400 3400)(-5225 3400);
WIRE 16 -1 (-5225 3450)(-5225 3400);
WIRE 16 -1 (-5400 3450)(-5225 3450);
WIRE 16 -1 (-5225 3500)(-5225 3450);
WIRE 16 -1 (-5400 3500)(-5225 3500);
WIRE 16 -1 (-5225 3550)(-5225 3500);
WIRE 16 -1 (-5400 3550)(-5225 3550);
WIRE 16 -1 (-5225 3600)(-5225 3550);
WIRE 16 -1 (-5225 3650)(-5225 3600);
WIRE 16 -1 (-5400 3600)(-5225 3600);
WIRE 16 -1 (-5400 3650)(-5225 3650);
WIRE 16 -1 (-5225 3700)(-5225 3650);
WIRE 16 -1 (-5400 3700)(-5225 3700);
WIRE 16 -1 (-5225 3750)(-5225 3700);
WIRE 16 -1 (-5400 3750)(-5225 3750);
WIRE 16 -1 (-5225 3800)(-5225 3750);
WIRE 16 -1 (-5400 3800)(-5225 3800);
WIRE 16 -1 (-5225 3850)(-5225 3800);
WIRE 16 -1 (-5400 3850)(-5225 3850);
WIRE 16 -1 (-5225 3900)(-5225 3850);
WIRE 16 -1 (-5400 3900)(-5225 3900);
WIRE 16 -1 (-5225 3950)(-5225 3900);
WIRE 16 -1 (-5400 3950)(-5225 3950);
WIRE 16 -1 (-5225 4000)(-5225 3950);
WIRE 16 -1 (-5400 4000)(-5225 4000);
WIRE 16 -1 (-5225 4050)(-5225 4000);
WIRE 16 -1 (-5400 4050)(-5225 4050);
WIRE 16 -1 (-5225 4100)(-5225 4050);
WIRE 16 -1 (-5225 4150)(-5225 4100);
WIRE 16 -1 (-5400 4100)(-5225 4100);
WIRE 16 -1 (-5400 4150)(-5225 4150);
WIRE 16 -1 (-5225 4200)(-5225 4150);
WIRE 16 -1 (-5400 4200)(-5225 4200);
WIRE 16 -1 (-5225 4250)(-5225 4200);
WIRE 16 -1 (-5400 4250)(-5225 4250);
WIRE 16 -1 (-5225 4300)(-5225 4250);
WIRE 16 -1 (-5400 4300)(-5225 4300);
WIRE 16 -1 (-5225 4350)(-5225 4300);
WIRE 16 -1 (-5400 4350)(-5225 4350);
WIRE 16 -1 (-5225 4400)(-5225 4350);
WIRE 16 -1 (-5400 4400)(-5225 4400);
WIRE 16 -1 (-5225 4450)(-5225 4400);
WIRE 16 -1 (-5400 4450)(-5225 4450);
WIRE 16 -1 (-5225 4500)(-5225 4450);
WIRE 16 -1 (-5400 4500)(-5225 4500);
WIRE 16 -1 (-5225 4550)(-5225 4500);
WIRE 16 -1 (-5400 4550)(-5225 4550);
WIRE 16 -1 (-5225 4600)(-5225 4550);
WIRE 16 -1 (-5400 4600)(-5225 4600);
WIRE 16 -1 (-5225 4650)(-5225 4600);
WIRE 16 -1 (-5225 4700)(-5225 4650);
WIRE 16 -1 (-5400 4650)(-5225 4650);
WIRE 16 -1 (-5400 4700)(-5225 4700);
WIRE 16 -1 (-5225 4750)(-5225 4700);
WIRE 16 -1 (-5400 4750)(-5225 4750);
WIRE 16 -1 (-5225 4800)(-5225 4750);
WIRE 16 -1 (-5400 4800)(-5225 4800);
WIRE 16 -1 (-5225 4850)(-5225 4800);
WIRE 16 -1 (-5400 4850)(-5225 4850);
WIRE 16 -1 (-5225 4900)(-5225 4850);
WIRE 16 -1 (-5400 4900)(-5225 4900);
WIRE 16 -1 (-5225 4950)(-5225 4900);
WIRE 16 -1 (-5400 4950)(-5225 4950);
WIRE 16 -1 (-5225 5000)(-5225 4950);
WIRE 16 -1 (-5400 5000)(-5225 5000);
WIRE 16 -1 (-5225 5050)(-5225 5000);
WIRE 16 -1 (-5400 5050)(-5225 5050);
WIRE 16 -1 (-5225 5100)(-5225 5050);
WIRE 16 -1 (-5400 5100)(-5225 5100);
WIRE 16 -1 (-5225 5150)(-5225 5100);
WIRE 16 -1 (-5225 5200)(-5225 5150);
WIRE 16 -1 (-5400 5150)(-5225 5150);
WIRE 16 -1 (-5400 5200)(-5225 5200);
WIRE 16 -1 (-5225 5250)(-5225 5200);
WIRE 16 -1 (-5400 5250)(-5225 5250);
WIRE 16 -1 (-5225 5300)(-5225 5250);
WIRE 16 -1 (-5400 5300)(-5225 5300);
WIRE 16 -1 (-5225 5350)(-5225 5300);
WIRE 16 -1 (-5400 5350)(-5225 5350);
WIRE 16 -1 (-5225 5400)(-5225 5350);
WIRE 16 -1 (-5400 5400)(-5225 5400);
WIRE 16 -1 (-5225 5450)(-5225 5400);
WIRE 16 -1 (-5400 5450)(-5225 5450);
WIRE 16 -1 (-5225 5500)(-5225 5450);
WIRE 16 -1 (-5400 5500)(-5225 5500);
WIRE 16 -1 (-5225 5550)(-5225 5500);
WIRE 16 -1 (-5400 5550)(-5225 5550);
WIRE 16 -1 (-5225 5600)(-5225 5550);
WIRE 16 -1 (-5400 5600)(-5225 5600);
WIRE 16 -1 (-5225 5650)(-5225 5600);
WIRE 16 -1 (-5225 5700)(-5225 5650);
WIRE 16 -1 (-5400 5650)(-5225 5650);
WIRE 16 -1 (-5400 5700)(-5225 5700);
WIRE 16 -1 (-5225 5750)(-5225 5700);
WIRE 16 -1 (-5400 5750)(-5225 5750);
WIRE 16 -1 (-5225 5800)(-5225 5750);
WIRE 16 -1 (-5400 5800)(-5225 5800);
WIRE 16 -1 (-5225 5850)(-5225 5800);
WIRE 16 -1 (-5400 5850)(-5225 5850);
WIRE 16 -1 (-5225 5900)(-5225 5850);
WIRE 16 -1 (-5400 5900)(-5225 5900);
WIRE 16 -1 (-5225 5950)(-5225 5900);
WIRE 16 -1 (-5400 5950)(-5225 5950);
WIRE 16 -1 (-5225 6000)(-5225 5950);
WIRE 16 -1 (-5400 6000)(-5225 6000);
WIRE 16 -1 (-5225 6050)(-5225 6000);
WIRE 16 -1 (-5400 6050)(-5225 6050);
WIRE 16 -1 (-5225 6100)(-5225 6050);
WIRE 16 -1 (-5400 6100)(-5225 6100);
WIRE 16 -1 (-5225 6150)(-5225 6100);
WIRE 16 -1 (-5225 6200)(-5225 6150);
WIRE 16 -1 (-5400 6150)(-5225 6150);
WIRE 16 -1 (-5400 6200)(-5225 6200);
WIRE 16 -1 (-5225 6250)(-5225 6200);
WIRE 16 -1 (-5400 6250)(-5225 6250);
WIRE 16 -1 (-5225 6300)(-5225 6250);
WIRE 16 -1 (-5400 6300)(-5225 6300);
WIRE 16 -1 (-5225 6350)(-5225 6300);
WIRE 16 -1 (-5400 6350)(-5225 6350);
WIRE 16 -1 (-4600 625)(-4425 625);
WIRE 16 -1 (-4600 675)(-4600 625);
WIRE 16 -1 (-4600 625)(-4600 525);
WIRE 16 -1 (-4425 675)(-4600 675);
WIRE 16 -1 (-4600 725)(-4600 675);
WIRE 16 -1 (-4600 775)(-4600 725);
WIRE 16 -1 (-4600 725)(-4425 725);
WIRE 16 -1 (-4600 775)(-4425 775);
WIRE 16 -1 (-4600 825)(-4600 775);
WIRE 16 -1 (-4600 825)(-4425 825);
WIRE 16 -1 (-4600 875)(-4600 825);
WIRE 16 -1 (-4600 875)(-4425 875);
WIRE 16 -1 (-4600 925)(-4600 875);
WIRE 16 -1 (-4425 925)(-4600 925);
WIRE 16 -1 (-4600 975)(-4600 925);
WIRE 16 -1 (-4600 1025)(-4600 975);
WIRE 16 -1 (-4600 975)(-4425 975);
WIRE 16 -1 (-4600 1025)(-4425 1025);
WIRE 16 -1 (-4600 1075)(-4600 1025);
WIRE 16 -1 (-4600 1075)(-4425 1075);
WIRE 16 -1 (-4600 1125)(-4600 1075);
WIRE 16 -1 (-4600 1125)(-4425 1125);
WIRE 16 -1 (-4600 1175)(-4600 1125);
WIRE 16 -1 (-4425 1175)(-4600 1175);
WIRE 16 -1 (-4600 1225)(-4600 1175);
WIRE 16 -1 (-4600 1225)(-4425 1225);
WIRE 16 -1 (-4600 1275)(-4600 1225);
WIRE 16 -1 (-4600 1325)(-4600 1275);
WIRE 16 -1 (-4600 1275)(-4425 1275);
WIRE 16 -1 (-4600 1325)(-4425 1325);
WIRE 16 -1 (-4600 1375)(-4600 1325);
WIRE 16 -1 (-4600 1375)(-4425 1375);
WIRE 16 -1 (-4600 1425)(-4600 1375);
WIRE 16 -1 (-4425 1425)(-4600 1425);
WIRE 16 -1 (-4600 1475)(-4600 1425);
WIRE 16 -1 (-4600 1475)(-4425 1475);
WIRE 16 -1 (-4600 1525)(-4600 1475);
WIRE 16 -1 (-4600 1575)(-4600 1525);
WIRE 16 -1 (-4600 1525)(-4425 1525);
WIRE 16 -1 (-4600 1575)(-4425 1575);
WIRE 16 -1 (-4600 1625)(-4600 1575);
WIRE 16 -1 (-4600 1625)(-4425 1625);
WIRE 16 -1 (-4600 1675)(-4600 1625);
WIRE 16 -1 (-4425 1675)(-4600 1675);
WIRE 16 -1 (-4600 1725)(-4600 1675);
WIRE 16 -1 (-4600 1725)(-4425 1725);
WIRE 16 -1 (-4600 1775)(-4600 1725);
WIRE 16 -1 (-4600 1825)(-4600 1775);
WIRE 16 -1 (-4600 1775)(-4425 1775);
WIRE 16 -1 (-4600 1825)(-4425 1825);
WIRE 16 -1 (-4600 1875)(-4600 1825);
WIRE 16 -1 (-4600 1875)(-4425 1875);
WIRE 16 -1 (-4600 1925)(-4600 1875);
WIRE 16 -1 (-4425 1925)(-4600 1925);
WIRE 16 -1 (-4600 1975)(-4600 1925);
WIRE 16 -1 (-4600 1975)(-4425 1975);
WIRE 16 -1 (-4600 2025)(-4600 1975);
WIRE 16 -1 (-4600 2075)(-4600 2025);
WIRE 16 -1 (-4600 2025)(-4425 2025);
WIRE 16 -1 (-4600 2075)(-4425 2075);
WIRE 16 -1 (-4600 2125)(-4600 2075);
WIRE 16 -1 (-4600 2125)(-4425 2125);
WIRE 16 -1 (-4600 2175)(-4600 2125);
WIRE 16 -1 (-4600 2175)(-4425 2175);
WIRE 16 -1 (-4600 2225)(-4600 2175);
WIRE 16 -1 (-4425 2225)(-4600 2225);
WIRE 16 -1 (-4600 2275)(-4600 2225);
WIRE 16 -1 (-4600 2325)(-4600 2275);
WIRE 16 -1 (-4600 2275)(-4425 2275);
WIRE 16 -1 (-4600 2325)(-4425 2325);
WIRE 16 -1 (-4600 2375)(-4600 2325);
WIRE 16 -1 (-4600 2375)(-4425 2375);
WIRE 16 -1 (-4600 2425)(-4600 2375);
WIRE 16 -1 (-4600 2425)(-4425 2425);
WIRE 16 -1 (-4600 2475)(-4600 2425);
WIRE 16 -1 (-4425 2475)(-4600 2475);
WIRE 16 -1 (-4600 2525)(-4600 2475);
WIRE 16 -1 (-4600 2575)(-4600 2525);
WIRE 16 -1 (-4600 2525)(-4425 2525);
WIRE 16 -1 (-4600 2575)(-4425 2575);
WIRE 16 -1 (-4600 2625)(-4600 2575);
WIRE 16 -1 (-4600 2625)(-4425 2625);
WIRE 16 -1 (-4600 2675)(-4600 2625);
WIRE 16 -1 (-4600 2675)(-4425 2675);
WIRE 16 -1 (-4600 2725)(-4600 2675);
WIRE 16 -1 (-4425 2725)(-4600 2725);
WIRE 16 -1 (-4600 2775)(-4600 2725);
WIRE 16 -1 (-4600 2825)(-4600 2775);
WIRE 16 -1 (-4600 2775)(-4425 2775);
WIRE 16 -1 (-4600 2825)(-4425 2825);
WIRE 16 -1 (-4600 2875)(-4600 2825);
WIRE 16 -1 (-4600 2875)(-4425 2875);
WIRE 16 -1 (-4600 2925)(-4600 2875);
WIRE 16 -1 (-4600 2925)(-4425 2925);
WIRE 16 -1 (-4600 2975)(-4600 2925);
WIRE 16 -1 (-4425 2975)(-4600 2975);
WIRE 16 -1 (-4600 3025)(-4600 2975);
WIRE 16 -1 (-4600 3075)(-4600 3025);
WIRE 16 -1 (-4600 3025)(-4425 3025);
WIRE 16 -1 (-4600 3075)(-4425 3075);
WIRE 16 -1 (-4600 3125)(-4600 3075);
WIRE 16 -1 (-4600 3125)(-4425 3125);
WIRE 16 -1 (-4600 3175)(-4600 3125);
WIRE 16 -1 (-4600 3175)(-4425 3175);
WIRE 16 -1 (-4600 3225)(-4600 3175);
WIRE 16 -1 (-4425 3225)(-4600 3225);
WIRE 16 -1 (-4600 3275)(-4600 3225);
WIRE 16 -1 (-4600 3275)(-4425 3275);
WIRE 16 -1 (-4600 3325)(-4600 3275);
WIRE 16 -1 (-4600 3375)(-4600 3325);
WIRE 16 -1 (-4600 3325)(-4425 3325);
WIRE 16 -1 (-4600 3375)(-4425 3375);
WIRE 16 -1 (-4600 3425)(-4600 3375);
WIRE 16 -1 (-4600 3425)(-4425 3425);
WIRE 16 -1 (-4600 3475)(-4600 3425);
WIRE 16 -1 (-4425 3475)(-4600 3475);
WIRE 16 -1 (-4600 3525)(-4600 3475);
WIRE 16 -1 (-4600 3525)(-4425 3525);
WIRE 16 -1 (-4600 3575)(-4600 3525);
WIRE 16 -1 (-4600 3625)(-4600 3575);
WIRE 16 -1 (-4600 3575)(-4425 3575);
WIRE 16 -1 (-4600 3625)(-4425 3625);
WIRE 16 -1 (-4600 3675)(-4600 3625);
WIRE 16 -1 (-4600 3675)(-4425 3675);
WIRE 16 -1 (-4600 3725)(-4600 3675);
WIRE 16 -1 (-4425 3725)(-4600 3725);
WIRE 16 -1 (-4600 3775)(-4600 3725);
WIRE 16 -1 (-4600 3775)(-4425 3775);
WIRE 16 -1 (-4600 3825)(-4600 3775);
WIRE 16 -1 (-4600 3875)(-4600 3825);
WIRE 16 -1 (-4600 3825)(-4425 3825);
WIRE 16 -1 (-4600 3875)(-4425 3875);
WIRE 16 -1 (-4600 3925)(-4600 3875);
WIRE 16 -1 (-4600 3925)(-4425 3925);
WIRE 16 -1 (-4600 3975)(-4600 3925);
WIRE 16 -1 (-4425 3975)(-4600 3975);
WIRE 16 -1 (-4600 4025)(-4600 3975);
WIRE 16 -1 (-4600 4025)(-4425 4025);
WIRE 16 -1 (-4600 4075)(-4600 4025);
WIRE 16 -1 (-4600 4125)(-4600 4075);
WIRE 16 -1 (-4600 4075)(-4425 4075);
WIRE 16 -1 (-4600 4125)(-4425 4125);
WIRE 16 -1 (-4600 4175)(-4600 4125);
WIRE 16 -1 (-4600 4175)(-4425 4175);
WIRE 16 -1 (-4600 4225)(-4600 4175);
WIRE 16 -1 (-4600 4225)(-4425 4225);
WIRE 16 -1 (-4600 4275)(-4600 4225);
WIRE 16 -1 (-4425 4275)(-4600 4275);
WIRE 16 -1 (-4600 4325)(-4600 4275);
WIRE 16 -1 (-4600 4375)(-4600 4325);
WIRE 16 -1 (-4600 4325)(-4425 4325);
WIRE 16 -1 (-4600 4375)(-4425 4375);
WIRE 16 -1 (-4600 4425)(-4600 4375);
WIRE 16 -1 (-4600 4425)(-4425 4425);
WIRE 16 -1 (-4600 4475)(-4600 4425);
WIRE 16 -1 (-4600 4475)(-4425 4475);
WIRE 16 -1 (-4600 4525)(-4600 4475);
WIRE 16 -1 (-4425 4525)(-4600 4525);
WIRE 16 -1 (-4600 4575)(-4600 4525);
WIRE 16 -1 (-4600 4625)(-4600 4575);
WIRE 16 -1 (-4600 4575)(-4425 4575);
WIRE 16 -1 (-4600 4625)(-4425 4625);
WIRE 16 -1 (-4600 4675)(-4600 4625);
WIRE 16 -1 (-4600 4675)(-4425 4675);
WIRE 16 -1 (-4600 4725)(-4600 4675);
WIRE 16 -1 (-4600 4725)(-4425 4725);
WIRE 16 -1 (-4600 4775)(-4600 4725);
WIRE 16 -1 (-4425 4775)(-4600 4775);
WIRE 16 -1 (-4600 4825)(-4600 4775);
WIRE 16 -1 (-4600 4875)(-4600 4825);
WIRE 16 -1 (-4600 4825)(-4425 4825);
WIRE 16 -1 (-4600 4875)(-4425 4875);
WIRE 16 -1 (-4600 4925)(-4600 4875);
WIRE 16 -1 (-4600 4925)(-4425 4925);
WIRE 16 -1 (-4600 4975)(-4600 4925);
WIRE 16 -1 (-4600 4975)(-4425 4975);
WIRE 16 -1 (-4600 5025)(-4600 4975);
WIRE 16 -1 (-4425 5025)(-4600 5025);
WIRE 16 -1 (-4600 5075)(-4600 5025);
WIRE 16 -1 (-4600 5125)(-4600 5075);
WIRE 16 -1 (-4600 5075)(-4425 5075);
WIRE 16 -1 (-4600 5125)(-4425 5125);
WIRE 16 -1 (-4600 5175)(-4600 5125);
WIRE 16 -1 (-4600 5175)(-4425 5175);
WIRE 16 -1 (-4600 5225)(-4600 5175);
WIRE 16 -1 (-4600 5225)(-4425 5225);
WIRE 16 -1 (-4600 5275)(-4600 5225);
WIRE 16 -1 (-4425 5275)(-4600 5275);
WIRE 16 -1 (-4600 5325)(-4600 5275);
WIRE 16 -1 (-4600 5325)(-4425 5325);
WIRE 16 -1 (-4600 5375)(-4600 5325);
WIRE 16 -1 (-4600 5425)(-4600 5375);
WIRE 16 -1 (-4600 5375)(-4425 5375);
WIRE 16 -1 (-4600 5425)(-4425 5425);
WIRE 16 -1 (-4600 5475)(-4600 5425);
WIRE 16 -1 (-4600 5475)(-4425 5475);
WIRE 16 -1 (-4600 5525)(-4600 5475);
WIRE 16 -1 (-4425 5525)(-4600 5525);
WIRE 16 -1 (-4600 5575)(-4600 5525);
WIRE 16 -1 (-4600 5575)(-4425 5575);
WIRE 16 -1 (-4600 5625)(-4600 5575);
WIRE 16 -1 (-4600 5675)(-4600 5625);
WIRE 16 -1 (-4600 5625)(-4425 5625);
WIRE 16 -1 (-4600 5675)(-4425 5675);
WIRE 16 -1 (-4600 5725)(-4600 5675);
WIRE 16 -1 (-4600 5725)(-4425 5725);
WIRE 16 -1 (-4600 5775)(-4600 5725);
WIRE 16 -1 (-4425 5775)(-4600 5775);
WIRE 16 -1 (-4600 5825)(-4600 5775);
WIRE 16 -1 (-4600 5825)(-4425 5825);
WIRE 16 -1 (-4600 5875)(-4600 5825);
WIRE 16 -1 (-4600 5925)(-4600 5875);
WIRE 16 -1 (-4600 5875)(-4425 5875);
WIRE 16 -1 (-4600 5925)(-4425 5925);
WIRE 16 -1 (-4600 5975)(-4600 5925);
WIRE 16 -1 (-4600 5975)(-4425 5975);
WIRE 16 -1 (-4600 6025)(-4600 5975);
WIRE 16 -1 (-4425 6025)(-4600 6025);
WIRE 16 -1 (-4600 6075)(-4600 6025);
WIRE 16 -1 (-4600 6075)(-4425 6075);
WIRE 16 -1 (-4600 6125)(-4600 6075);
WIRE 16 -1 (-4600 6175)(-4600 6125);
WIRE 16 -1 (-4600 6125)(-4425 6125);
WIRE 16 -1 (-4600 6175)(-4425 6175);
WIRE 16 -1 (-4600 6225)(-4600 6175);
WIRE 16 -1 (-4600 6225)(-4425 6225);
WIRE 16 -1 (-4600 6275)(-4600 6225);
WIRE 16 -1 (-4425 6275)(-4600 6275);
WIRE 16 -1 (-4600 6325)(-4600 6275);
WIRE 16 -1 (-4600 6325)(-4425 6325);
WIRE 16 -1 (-3150 500)(-3150 625);
WIRE 16 -1 (-3150 675)(-3150 625);
WIRE 16 -1 (-3325 625)(-3150 625);
WIRE 16 -1 (-3325 675)(-3150 675);
WIRE 16 -1 (-3150 725)(-3150 675);
WIRE 16 -1 (-3325 725)(-3150 725);
WIRE 16 -1 (-3150 775)(-3150 725);
WIRE 16 -1 (-3150 825)(-3150 775);
WIRE 16 -1 (-3325 775)(-3150 775);
WIRE 16 -1 (-3325 825)(-3150 825);
WIRE 16 -1 (-3150 875)(-3150 825);
WIRE 16 -1 (-3325 875)(-3150 875);
WIRE 16 -1 (-3150 925)(-3150 875);
WIRE 16 -1 (-3325 925)(-3150 925);
WIRE 16 -1 (-3150 975)(-3150 925);
WIRE 16 -1 (-3325 975)(-3150 975);
WIRE 16 -1 (-3150 1025)(-3150 975);
WIRE 16 -1 (-3150 1075)(-3150 1025);
WIRE 16 -1 (-3325 1025)(-3150 1025);
WIRE 16 -1 (-3325 1075)(-3150 1075);
WIRE 16 -1 (-3150 1125)(-3150 1075);
WIRE 16 -1 (-3325 1125)(-3150 1125);
WIRE 16 -1 (-3150 1175)(-3150 1125);
WIRE 16 -1 (-3325 1175)(-3150 1175);
WIRE 16 -1 (-3150 1225)(-3150 1175);
WIRE 16 -1 (-3325 1225)(-3150 1225);
WIRE 16 -1 (-3150 1275)(-3150 1225);
WIRE 16 -1 (-3325 1275)(-3150 1275);
WIRE 16 -1 (-3150 1325)(-3150 1275);
WIRE 16 -1 (-3150 1375)(-3150 1325);
WIRE 16 -1 (-3325 1325)(-3150 1325);
WIRE 16 -1 (-3325 1375)(-3150 1375);
WIRE 16 -1 (-3150 1425)(-3150 1375);
WIRE 16 -1 (-3325 1425)(-3150 1425);
WIRE 16 -1 (-3150 1475)(-3150 1425);
WIRE 16 -1 (-3325 1475)(-3150 1475);
WIRE 16 -1 (-3150 1525)(-3150 1475);
WIRE 16 -1 (-3325 1525)(-3150 1525);
WIRE 16 -1 (-3150 1575)(-3150 1525);
WIRE 16 -1 (-3150 1625)(-3150 1575);
WIRE 16 -1 (-3325 1575)(-3150 1575);
WIRE 16 -1 (-3325 1625)(-3150 1625);
WIRE 16 -1 (-3150 1675)(-3150 1625);
WIRE 16 -1 (-3325 1675)(-3150 1675);
WIRE 16 -1 (-3150 1725)(-3150 1675);
WIRE 16 -1 (-3325 1725)(-3150 1725);
WIRE 16 -1 (-3150 1775)(-3150 1725);
WIRE 16 -1 (-3325 1775)(-3150 1775);
WIRE 16 -1 (-3150 1825)(-3150 1775);
WIRE 16 -1 (-3150 1875)(-3150 1825);
WIRE 16 -1 (-3325 1825)(-3150 1825);
WIRE 16 -1 (-3325 1875)(-3150 1875);
WIRE 16 -1 (-3150 1925)(-3150 1875);
WIRE 16 -1 (-3325 1925)(-3150 1925);
WIRE 16 -1 (-3150 1975)(-3150 1925);
WIRE 16 -1 (-3325 1975)(-3150 1975);
WIRE 16 -1 (-3150 2025)(-3150 1975);
WIRE 16 -1 (-3325 2025)(-3150 2025);
WIRE 16 -1 (-3150 2075)(-3150 2025);
WIRE 16 -1 (-3150 2125)(-3150 2075);
WIRE 16 -1 (-3325 2075)(-3150 2075);
WIRE 16 -1 (-3325 2125)(-3150 2125);
WIRE 16 -1 (-3150 2175)(-3150 2125);
WIRE 16 -1 (-3325 2175)(-3150 2175);
WIRE 16 -1 (-3150 2225)(-3150 2175);
WIRE 16 -1 (-3325 2225)(-3150 2225);
WIRE 16 -1 (-3150 2275)(-3150 2225);
WIRE 16 -1 (-3325 2275)(-3150 2275);
WIRE 16 -1 (-3150 2325)(-3150 2275);
WIRE 16 -1 (-3150 2375)(-3150 2325);
WIRE 16 -1 (-3325 2325)(-3150 2325);
WIRE 16 -1 (-3325 2375)(-3150 2375);
WIRE 16 -1 (-3150 2425)(-3150 2375);
WIRE 16 -1 (-3325 2425)(-3150 2425);
WIRE 16 -1 (-3150 2475)(-3150 2425);
WIRE 16 -1 (-3325 2475)(-3150 2475);
WIRE 16 -1 (-3150 2525)(-3150 2475);
WIRE 16 -1 (-3325 2525)(-3150 2525);
WIRE 16 -1 (-3150 2575)(-3150 2525);
WIRE 16 -1 (-3150 2625)(-3150 2575);
WIRE 16 -1 (-3325 2575)(-3150 2575);
WIRE 16 -1 (-3325 2625)(-3150 2625);
WIRE 16 -1 (-3150 2675)(-3150 2625);
WIRE 16 -1 (-3325 2675)(-3150 2675);
WIRE 16 -1 (-3150 2725)(-3150 2675);
WIRE 16 -1 (-3325 2725)(-3150 2725);
WIRE 16 -1 (-3150 2775)(-3150 2725);
WIRE 16 -1 (-3325 2775)(-3150 2775);
WIRE 16 -1 (-3150 2825)(-3150 2775);
WIRE 16 -1 (-3150 2875)(-3150 2825);
WIRE 16 -1 (-3325 2825)(-3150 2825);
WIRE 16 -1 (-3325 2875)(-3150 2875);
WIRE 16 -1 (-3150 2925)(-3150 2875);
WIRE 16 -1 (-3325 2925)(-3150 2925);
WIRE 16 -1 (-3150 2975)(-3150 2925);
WIRE 16 -1 (-3325 2975)(-3150 2975);
WIRE 16 -1 (-3150 3025)(-3150 2975);
WIRE 16 -1 (-3325 3025)(-3150 3025);
WIRE 16 -1 (-3150 3075)(-3150 3025);
WIRE 16 -1 (-3150 3125)(-3150 3075);
WIRE 16 -1 (-3325 3075)(-3150 3075);
WIRE 16 -1 (-3325 3125)(-3150 3125);
WIRE 16 -1 (-3150 3175)(-3150 3125);
WIRE 16 -1 (-3325 3175)(-3150 3175);
WIRE 16 -1 (-3150 3225)(-3150 3175);
WIRE 16 -1 (-3325 3225)(-3150 3225);
WIRE 16 -1 (-3150 3275)(-3150 3225);
WIRE 16 -1 (-3325 3275)(-3150 3275);
WIRE 16 -1 (-3150 3325)(-3150 3275);
WIRE 16 -1 (-3325 3325)(-3150 3325);
WIRE 16 -1 (-3150 3375)(-3150 3325);
WIRE 16 -1 (-3150 3425)(-3150 3375);
WIRE 16 -1 (-3325 3375)(-3150 3375);
WIRE 16 -1 (-3325 3425)(-3150 3425);
WIRE 16 -1 (-3150 3475)(-3150 3425);
WIRE 16 -1 (-3325 3475)(-3150 3475);
WIRE 16 -1 (-3150 3525)(-3150 3475);
WIRE 16 -1 (-3325 3525)(-3150 3525);
WIRE 16 -1 (-3150 3575)(-3150 3525);
WIRE 16 -1 (-3325 3575)(-3150 3575);
WIRE 16 -1 (-3150 3625)(-3150 3575);
WIRE 16 -1 (-3150 3675)(-3150 3625);
WIRE 16 -1 (-3325 3625)(-3150 3625);
WIRE 16 -1 (-3325 3675)(-3150 3675);
WIRE 16 -1 (-3150 3725)(-3150 3675);
WIRE 16 -1 (-3325 3725)(-3150 3725);
WIRE 16 -1 (-3150 3775)(-3150 3725);
WIRE 16 -1 (-3325 3775)(-3150 3775);
WIRE 16 -1 (-3150 3825)(-3150 3775);
WIRE 16 -1 (-3325 3825)(-3150 3825);
WIRE 16 -1 (-3150 3875)(-3150 3825);
WIRE 16 -1 (-3150 3925)(-3150 3875);
WIRE 16 -1 (-3325 3875)(-3150 3875);
WIRE 16 -1 (-3325 3925)(-3150 3925);
WIRE 16 -1 (-3150 3975)(-3150 3925);
WIRE 16 -1 (-3325 3975)(-3150 3975);
WIRE 16 -1 (-3150 4025)(-3150 3975);
WIRE 16 -1 (-3325 4025)(-3150 4025);
WIRE 16 -1 (-3150 4075)(-3150 4025);
WIRE 16 -1 (-3325 4075)(-3150 4075);
WIRE 16 -1 (-3150 4125)(-3150 4075);
WIRE 16 -1 (-3150 4175)(-3150 4125);
WIRE 16 -1 (-3325 4125)(-3150 4125);
WIRE 16 -1 (-3325 4175)(-3150 4175);
WIRE 16 -1 (-3150 4225)(-3150 4175);
WIRE 16 -1 (-3325 4225)(-3150 4225);
WIRE 16 -1 (-3150 4275)(-3150 4225);
WIRE 16 -1 (-3325 4275)(-3150 4275);
WIRE 16 -1 (-3150 4325)(-3150 4275);
WIRE 16 -1 (-3325 4325)(-3150 4325);
WIRE 16 -1 (-3150 4375)(-3150 4325);
WIRE 16 -1 (-3150 4425)(-3150 4375);
WIRE 16 -1 (-3325 4375)(-3150 4375);
WIRE 16 -1 (-3325 4425)(-3150 4425);
WIRE 16 -1 (-3150 4475)(-3150 4425);
WIRE 16 -1 (-3325 4475)(-3150 4475);
WIRE 16 -1 (-3150 4525)(-3150 4475);
WIRE 16 -1 (-3325 4525)(-3150 4525);
WIRE 16 -1 (-3150 4575)(-3150 4525);
WIRE 16 -1 (-3325 4575)(-3150 4575);
WIRE 16 -1 (-3150 4625)(-3150 4575);
WIRE 16 -1 (-3150 4675)(-3150 4625);
WIRE 16 -1 (-3325 4625)(-3150 4625);
WIRE 16 -1 (-3325 4675)(-3150 4675);
WIRE 16 -1 (-3150 4725)(-3150 4675);
WIRE 16 -1 (-3325 4725)(-3150 4725);
WIRE 16 -1 (-3150 4775)(-3150 4725);
WIRE 16 -1 (-3325 4775)(-3150 4775);
WIRE 16 -1 (-3150 4825)(-3150 4775);
WIRE 16 -1 (-3325 4825)(-3150 4825);
WIRE 16 -1 (-3150 4875)(-3150 4825);
WIRE 16 -1 (-3150 4925)(-3150 4875);
WIRE 16 -1 (-3325 4875)(-3150 4875);
WIRE 16 -1 (-3325 4925)(-3150 4925);
WIRE 16 -1 (-3150 4975)(-3150 4925);
WIRE 16 -1 (-3325 4975)(-3150 4975);
WIRE 16 -1 (-3150 5025)(-3150 4975);
WIRE 16 -1 (-3325 5025)(-3150 5025);
WIRE 16 -1 (-3150 5075)(-3150 5025);
WIRE 16 -1 (-3325 5075)(-3150 5075);
WIRE 16 -1 (-3150 5125)(-3150 5075);
WIRE 16 -1 (-3150 5175)(-3150 5125);
WIRE 16 -1 (-3325 5125)(-3150 5125);
WIRE 16 -1 (-3325 5175)(-3150 5175);
WIRE 16 -1 (-3150 5225)(-3150 5175);
WIRE 16 -1 (-3325 5225)(-3150 5225);
WIRE 16 -1 (-3150 5275)(-3150 5225);
WIRE 16 -1 (-3325 5275)(-3150 5275);
WIRE 16 -1 (-3150 5325)(-3150 5275);
WIRE 16 -1 (-3325 5325)(-3150 5325);
WIRE 16 -1 (-3150 5375)(-3150 5325);
WIRE 16 -1 (-3325 5375)(-3150 5375);
WIRE 16 -1 (-3150 5425)(-3150 5375);
WIRE 16 -1 (-3150 5475)(-3150 5425);
WIRE 16 -1 (-3325 5425)(-3150 5425);
WIRE 16 -1 (-3325 5475)(-3150 5475);
WIRE 16 -1 (-3150 5525)(-3150 5475);
WIRE 16 -1 (-3325 5525)(-3150 5525);
WIRE 16 -1 (-3150 5575)(-3150 5525);
WIRE 16 -1 (-3325 5575)(-3150 5575);
WIRE 16 -1 (-3150 5625)(-3150 5575);
WIRE 16 -1 (-3325 5625)(-3150 5625);
WIRE 16 -1 (-3150 5675)(-3150 5625);
WIRE 16 -1 (-3150 5725)(-3150 5675);
WIRE 16 -1 (-3325 5675)(-3150 5675);
WIRE 16 -1 (-3325 5725)(-3150 5725);
WIRE 16 -1 (-3150 5775)(-3150 5725);
WIRE 16 -1 (-3325 5775)(-3150 5775);
WIRE 16 -1 (-3150 5825)(-3150 5775);
WIRE 16 -1 (-3325 5825)(-3150 5825);
WIRE 16 -1 (-3150 5875)(-3150 5825);
WIRE 16 -1 (-3325 5875)(-3150 5875);
WIRE 16 -1 (-3150 5925)(-3150 5875);
WIRE 16 -1 (-3150 5975)(-3150 5925);
WIRE 16 -1 (-3325 5925)(-3150 5925);
WIRE 16 -1 (-3325 5975)(-3150 5975);
WIRE 16 -1 (-3150 6025)(-3150 5975);
WIRE 16 -1 (-3325 6025)(-3150 6025);
WIRE 16 -1 (-3150 6075)(-3150 6025);
WIRE 16 -1 (-3325 6075)(-3150 6075);
WIRE 16 -1 (-3150 6125)(-3150 6075);
WIRE 16 -1 (-3325 6125)(-3150 6125);
WIRE 16 -1 (-3150 6175)(-3150 6125);
WIRE 16 -1 (-3150 6225)(-3150 6175);
WIRE 16 -1 (-3325 6175)(-3150 6175);
WIRE 16 -1 (-3325 6225)(-3150 6225);
WIRE 16 -1 (-3150 6275)(-3150 6225);
WIRE 16 -1 (-3325 6275)(-3150 6275);
WIRE 16 -1 (-3150 6325)(-3150 6275);
WIRE 16 -1 (-3325 6325)(-3150 6325);
WIRE 16 -1 (-3150 6375)(-3150 6325);
WIRE 16 -1 (-3325 6375)(-3150 6375);
WIRE 16 -1 (-3150 6425)(-3150 6375);
WIRE 16 -1 (-3325 6425)(-3150 6425);
WIRE 16 -1 (-2350 550)(-2525 550);
WIRE 16 -1 (-2525 600)(-2525 550);
WIRE 16 -1 (-2525 550)(-2525 500);
WIRE 16 -1 (-2350 600)(-2525 600);
WIRE 16 -1 (-2525 650)(-2525 600);
WIRE 16 -1 (-2525 650)(-2350 650);
WIRE 16 -1 (-2525 700)(-2525 650);
WIRE 16 -1 (-2350 700)(-2525 700);
WIRE 16 -1 (-2525 750)(-2525 700);
WIRE 16 -1 (-2525 800)(-2525 750);
WIRE 16 -1 (-2525 750)(-2350 750);
WIRE 16 -1 (-2525 800)(-2350 800);
WIRE 16 -1 (-2525 850)(-2525 800);
WIRE 16 -1 (-2525 850)(-2350 850);
WIRE 16 -1 (-2525 900)(-2525 850);
WIRE 16 -1 (-2525 900)(-2350 900);
WIRE 16 -1 (-2525 950)(-2525 900);
WIRE 16 -1 (-2350 950)(-2525 950);
WIRE 16 -1 (-2525 1000)(-2525 950);
WIRE 16 -1 (-2525 1050)(-2525 1000);
WIRE 16 -1 (-2525 1000)(-2350 1000);
WIRE 16 -1 (-2525 1050)(-2350 1050);
WIRE 16 -1 (-2525 1100)(-2525 1050);
WIRE 16 -1 (-2525 1100)(-2350 1100);
WIRE 16 -1 (-2525 1150)(-2525 1100);
WIRE 16 -1 (-2525 1150)(-2350 1150);
WIRE 16 -1 (-2525 1200)(-2525 1150);
WIRE 16 -1 (-2350 1200)(-2525 1200);
WIRE 16 -1 (-2525 1250)(-2525 1200);
WIRE 16 -1 (-2525 1300)(-2525 1250);
WIRE 16 -1 (-2525 1250)(-2350 1250);
WIRE 16 -1 (-2525 1300)(-2350 1300);
WIRE 16 -1 (-2525 1350)(-2525 1300);
WIRE 16 -1 (-2525 1350)(-2350 1350);
WIRE 16 -1 (-2525 1400)(-2525 1350);
WIRE 16 -1 (-2525 1400)(-2350 1400);
WIRE 16 -1 (-2525 1450)(-2525 1400);
WIRE 16 -1 (-2350 1450)(-2525 1450);
WIRE 16 -1 (-2525 1500)(-2525 1450);
WIRE 16 -1 (-2525 1550)(-2525 1500);
WIRE 16 -1 (-2525 1500)(-2350 1500);
WIRE 16 -1 (-2525 1550)(-2350 1550);
WIRE 16 -1 (-2525 1600)(-2525 1550);
WIRE 16 -1 (-2525 1600)(-2350 1600);
WIRE 16 -1 (-2525 1650)(-2525 1600);
WIRE 16 -1 (-2525 1650)(-2350 1650);
WIRE 16 -1 (-2525 1700)(-2525 1650);
WIRE 16 -1 (-2350 1700)(-2525 1700);
WIRE 16 -1 (-2525 1750)(-2525 1700);
WIRE 16 -1 (-2525 1800)(-2525 1750);
WIRE 16 -1 (-2525 1750)(-2350 1750);
WIRE 16 -1 (-2525 1800)(-2350 1800);
WIRE 16 -1 (-2525 1850)(-2525 1800);
WIRE 16 -1 (-2525 1850)(-2350 1850);
WIRE 16 -1 (-2525 1900)(-2525 1850);
WIRE 16 -1 (-2525 1900)(-2350 1900);
WIRE 16 -1 (-2525 1950)(-2525 1900);
WIRE 16 -1 (-2350 1950)(-2525 1950);
WIRE 16 -1 (-2525 2000)(-2525 1950);
WIRE 16 -1 (-2525 2050)(-2525 2000);
WIRE 16 -1 (-2525 2000)(-2350 2000);
WIRE 16 -1 (-2525 2050)(-2350 2050);
WIRE 16 -1 (-2525 2100)(-2525 2050);
WIRE 16 -1 (-2525 2100)(-2350 2100);
WIRE 16 -1 (-2525 2150)(-2525 2100);
WIRE 16 -1 (-2525 2150)(-2350 2150);
WIRE 16 -1 (-2525 2200)(-2525 2150);
WIRE 16 -1 (-2525 2200)(-2350 2200);
WIRE 16 -1 (-2525 2250)(-2525 2200);
WIRE 16 -1 (-2350 2250)(-2525 2250);
WIRE 16 -1 (-2525 2300)(-2525 2250);
WIRE 16 -1 (-2525 2350)(-2525 2300);
WIRE 16 -1 (-2525 2300)(-2350 2300);
WIRE 16 -1 (-2525 2350)(-2350 2350);
WIRE 16 -1 (-2525 2400)(-2525 2350);
WIRE 16 -1 (-2525 2400)(-2350 2400);
WIRE 16 -1 (-2525 2450)(-2525 2400);
WIRE 16 -1 (-2525 2450)(-2350 2450);
WIRE 16 -1 (-2525 2500)(-2525 2450);
WIRE 16 -1 (-2350 2500)(-2525 2500);
WIRE 16 -1 (-2525 2550)(-2525 2500);
WIRE 16 -1 (-2525 2600)(-2525 2550);
WIRE 16 -1 (-2525 2550)(-2350 2550);
WIRE 16 -1 (-2525 2600)(-2350 2600);
WIRE 16 -1 (-2525 2650)(-2525 2600);
WIRE 16 -1 (-2525 2650)(-2350 2650);
WIRE 16 -1 (-2525 2700)(-2525 2650);
WIRE 16 -1 (-2525 2700)(-2350 2700);
WIRE 16 -1 (-2525 2750)(-2525 2700);
WIRE 16 -1 (-2350 2750)(-2525 2750);
WIRE 16 -1 (-2525 2800)(-2525 2750);
WIRE 16 -1 (-2525 2850)(-2525 2800);
WIRE 16 -1 (-2525 2800)(-2350 2800);
WIRE 16 -1 (-2525 2850)(-2350 2850);
WIRE 16 -1 (-2525 2900)(-2525 2850);
WIRE 16 -1 (-2525 2900)(-2350 2900);
WIRE 16 -1 (-2525 2950)(-2525 2900);
WIRE 16 -1 (-2525 2950)(-2350 2950);
WIRE 16 -1 (-2525 3000)(-2525 2950);
WIRE 16 -1 (-2350 3000)(-2525 3000);
WIRE 16 -1 (-2525 3050)(-2525 3000);
WIRE 16 -1 (-2525 3100)(-2525 3050);
WIRE 16 -1 (-2525 3050)(-2350 3050);
WIRE 16 -1 (-2525 3100)(-2350 3100);
WIRE 16 -1 (-2525 3150)(-2525 3100);
WIRE 16 -1 (-2525 3150)(-2350 3150);
WIRE 16 -1 (-2525 3200)(-2525 3150);
WIRE 16 -1 (-2525 3200)(-2350 3200);
WIRE 16 -1 (-2525 3250)(-2525 3200);
WIRE 16 -1 (-2350 3250)(-2525 3250);
WIRE 16 -1 (-2525 3300)(-2525 3250);
WIRE 16 -1 (-2525 3350)(-2525 3300);
WIRE 16 -1 (-2525 3300)(-2350 3300);
WIRE 16 -1 (-2525 3350)(-2350 3350);
WIRE 16 -1 (-2525 3400)(-2525 3350);
WIRE 16 -1 (-2525 3400)(-2350 3400);
WIRE 16 -1 (-2525 3450)(-2525 3400);
WIRE 16 -1 (-2525 3450)(-2350 3450);
WIRE 16 -1 (-2525 3500)(-2525 3450);
WIRE 16 -1 (-2350 3500)(-2525 3500);
WIRE 16 -1 (-2525 3550)(-2525 3500);
WIRE 16 -1 (-2525 3600)(-2525 3550);
WIRE 16 -1 (-2525 3550)(-2350 3550);
WIRE 16 -1 (-2525 3600)(-2350 3600);
WIRE 16 -1 (-2525 3650)(-2525 3600);
WIRE 16 -1 (-2525 3650)(-2350 3650);
WIRE 16 -1 (-2525 3700)(-2525 3650);
WIRE 16 -1 (-2525 3700)(-2350 3700);
WIRE 16 -1 (-2525 3750)(-2525 3700);
WIRE 16 -1 (-2350 3750)(-2525 3750);
WIRE 16 -1 (-2525 3800)(-2525 3750);
WIRE 16 -1 (-2525 3850)(-2525 3800);
WIRE 16 -1 (-2525 3800)(-2350 3800);
WIRE 16 -1 (-2525 3850)(-2350 3850);
WIRE 16 -1 (-2525 3900)(-2525 3850);
WIRE 16 -1 (-2525 3900)(-2350 3900);
WIRE 16 -1 (-2525 3950)(-2525 3900);
WIRE 16 -1 (-2525 3950)(-2350 3950);
WIRE 16 -1 (-2525 4000)(-2525 3950);
WIRE 16 -1 (-2350 4000)(-2525 4000);
WIRE 16 -1 (-2525 4050)(-2525 4000);
WIRE 16 -1 (-2525 4100)(-2525 4050);
WIRE 16 -1 (-2525 4050)(-2350 4050);
WIRE 16 -1 (-2525 4100)(-2350 4100);
WIRE 16 -1 (-2525 4150)(-2525 4100);
WIRE 16 -1 (-2525 4150)(-2350 4150);
WIRE 16 -1 (-2525 4200)(-2525 4150);
WIRE 16 -1 (-2525 4200)(-2350 4200);
WIRE 16 -1 (-2525 4250)(-2525 4200);
WIRE 16 -1 (-2525 4250)(-2350 4250);
WIRE 16 -1 (-2525 4300)(-2525 4250);
WIRE 16 -1 (-2350 4300)(-2525 4300);
WIRE 16 -1 (-2525 4350)(-2525 4300);
WIRE 16 -1 (-2525 4400)(-2525 4350);
WIRE 16 -1 (-2525 4350)(-2350 4350);
WIRE 16 -1 (-2525 4400)(-2350 4400);
WIRE 16 -1 (-2525 4450)(-2525 4400);
WIRE 16 -1 (-2525 4450)(-2350 4450);
WIRE 16 -1 (-2525 4500)(-2525 4450);
WIRE 16 -1 (-2525 4500)(-2350 4500);
WIRE 16 -1 (-2525 4550)(-2525 4500);
WIRE 16 -1 (-2350 4550)(-2525 4550);
WIRE 16 -1 (-2525 4600)(-2525 4550);
WIRE 16 -1 (-2525 4650)(-2525 4600);
WIRE 16 -1 (-2525 4600)(-2350 4600);
WIRE 16 -1 (-2525 4650)(-2350 4650);
WIRE 16 -1 (-2525 4700)(-2525 4650);
WIRE 16 -1 (-2525 4700)(-2350 4700);
WIRE 16 -1 (-2525 4750)(-2525 4700);
WIRE 16 -1 (-2525 4750)(-2350 4750);
WIRE 16 -1 (-2525 4800)(-2525 4750);
WIRE 16 -1 (-2350 4800)(-2525 4800);
WIRE 16 -1 (-2525 4850)(-2525 4800);
WIRE 16 -1 (-2525 4900)(-2525 4850);
WIRE 16 -1 (-2525 4850)(-2350 4850);
WIRE 16 -1 (-2525 4900)(-2350 4900);
WIRE 16 -1 (-2525 4950)(-2525 4900);
WIRE 16 -1 (-2525 4950)(-2350 4950);
WIRE 16 -1 (-2525 5000)(-2525 4950);
WIRE 16 -1 (-2525 5000)(-2350 5000);
WIRE 16 -1 (-2525 5050)(-2525 5000);
WIRE 16 -1 (-2350 5050)(-2525 5050);
WIRE 16 -1 (-2525 5100)(-2525 5050);
WIRE 16 -1 (-2525 5150)(-2525 5100);
WIRE 16 -1 (-2525 5100)(-2350 5100);
WIRE 16 -1 (-2525 5150)(-2350 5150);
WIRE 16 -1 (-2525 5200)(-2525 5150);
WIRE 16 -1 (-2525 5200)(-2350 5200);
WIRE 16 -1 (-2525 5250)(-2525 5200);
WIRE 16 -1 (-2525 5250)(-2350 5250);
WIRE 16 -1 (-2525 5300)(-2525 5250);
WIRE 16 -1 (-2350 5300)(-2525 5300);
WIRE 16 -1 (-2525 5350)(-2525 5300);
WIRE 16 -1 (-2525 5400)(-2525 5350);
WIRE 16 -1 (-2525 5350)(-2350 5350);
WIRE 16 -1 (-2525 5400)(-2350 5400);
WIRE 16 -1 (-2525 5450)(-2525 5400);
WIRE 16 -1 (-2525 5450)(-2350 5450);
WIRE 16 -1 (-2525 5500)(-2525 5450);
WIRE 16 -1 (-2525 5500)(-2350 5500);
WIRE 16 -1 (-2525 5550)(-2525 5500);
WIRE 16 -1 (-2350 5550)(-2525 5550);
WIRE 16 -1 (-2525 5600)(-2525 5550);
WIRE 16 -1 (-2525 5650)(-2525 5600);
WIRE 16 -1 (-2525 5600)(-2350 5600);
WIRE 16 -1 (-2525 5650)(-2350 5650);
WIRE 16 -1 (-2525 5700)(-2525 5650);
WIRE 16 -1 (-2525 5700)(-2350 5700);
WIRE 16 -1 (-2525 5750)(-2525 5700);
WIRE 16 -1 (-2525 5750)(-2350 5750);
WIRE 16 -1 (-2525 5800)(-2525 5750);
WIRE 16 -1 (-2350 5800)(-2525 5800);
WIRE 16 -1 (-2525 5850)(-2525 5800);
WIRE 16 -1 (-2525 5900)(-2525 5850);
WIRE 16 -1 (-2525 5850)(-2350 5850);
WIRE 16 -1 (-2525 5900)(-2350 5900);
WIRE 16 -1 (-2525 5950)(-2525 5900);
WIRE 16 -1 (-2525 5950)(-2350 5950);
WIRE 16 -1 (-2525 6000)(-2525 5950);
WIRE 16 -1 (-2525 6000)(-2350 6000);
WIRE 16 -1 (-2525 6050)(-2525 6000);
WIRE 16 -1 (-2350 6050)(-2525 6050);
WIRE 16 -1 (-2525 6100)(-2525 6050);
WIRE 16 -1 (-2525 6150)(-2525 6100);
WIRE 16 -1 (-2525 6100)(-2350 6100);
WIRE 16 -1 (-2525 6150)(-2350 6150);
WIRE 16 -1 (-2525 6200)(-2525 6150);
WIRE 16 -1 (-2525 6200)(-2350 6200);
WIRE 16 -1 (-2525 6250)(-2525 6200);
WIRE 16 -1 (-2525 6250)(-2350 6250);
WIRE 16 -1 (-2525 6300)(-2525 6250);
WIRE 16 -1 (-2350 6300)(-2525 6300);
WIRE 16 -1 (-2525 6350)(-2525 6300);
WIRE 16 -1 (-2525 6350)(-2350 6350);
WIRE 16 -1 (-1075 500)(-1075 550);
WIRE 16 -1 (-1075 600)(-1075 550);
WIRE 16 -1 (-1250 550)(-1075 550);
WIRE 16 -1 (-1250 600)(-1075 600);
WIRE 16 -1 (-1075 650)(-1075 600);
WIRE 16 -1 (-1250 650)(-1075 650);
WIRE 16 -1 (-1075 700)(-1075 650);
WIRE 16 -1 (-1250 700)(-1075 700);
WIRE 16 -1 (-1075 750)(-1075 700);
WIRE 16 -1 (-1250 750)(-1075 750);
WIRE 16 -1 (-1075 800)(-1075 750);
WIRE 16 -1 (-1075 850)(-1075 800);
WIRE 16 -1 (-1250 800)(-1075 800);
WIRE 16 -1 (-1250 850)(-1075 850);
WIRE 16 -1 (-1075 900)(-1075 850);
WIRE 16 -1 (-1250 900)(-1075 900);
WIRE 16 -1 (-1075 950)(-1075 900);
WIRE 16 -1 (-1250 950)(-1075 950);
WIRE 16 -1 (-1075 1000)(-1075 950);
WIRE 16 -1 (-1250 1000)(-1075 1000);
WIRE 16 -1 (-1075 1050)(-1075 1000);
WIRE 16 -1 (-1075 1100)(-1075 1050);
WIRE 16 -1 (-1250 1050)(-1075 1050);
WIRE 16 -1 (-1250 1100)(-1075 1100);
WIRE 16 -1 (-1075 1150)(-1075 1100);
WIRE 16 -1 (-1250 1150)(-1075 1150);
WIRE 16 -1 (-1075 1200)(-1075 1150);
WIRE 16 -1 (-1250 1200)(-1075 1200);
WIRE 16 -1 (-1075 1250)(-1075 1200);
WIRE 16 -1 (-1250 1250)(-1075 1250);
WIRE 16 -1 (-1075 1300)(-1075 1250);
WIRE 16 -1 (-1075 1350)(-1075 1300);
WIRE 16 -1 (-1250 1300)(-1075 1300);
WIRE 16 -1 (-1250 1350)(-1075 1350);
WIRE 16 -1 (-1075 1400)(-1075 1350);
WIRE 16 -1 (-1250 1400)(-1075 1400);
WIRE 16 -1 (-1075 1450)(-1075 1400);
WIRE 16 -1 (-1250 1450)(-1075 1450);
WIRE 16 -1 (-1075 1500)(-1075 1450);
WIRE 16 -1 (-1250 1500)(-1075 1500);
WIRE 16 -1 (-1075 1550)(-1075 1500);
WIRE 16 -1 (-1075 1600)(-1075 1550);
WIRE 16 -1 (-1250 1550)(-1075 1550);
WIRE 16 -1 (-1250 1600)(-1075 1600);
WIRE 16 -1 (-1075 1650)(-1075 1600);
WIRE 16 -1 (-1250 1650)(-1075 1650);
WIRE 16 -1 (-1075 1700)(-1075 1650);
WIRE 16 -1 (-1250 1700)(-1075 1700);
WIRE 16 -1 (-1075 1750)(-1075 1700);
WIRE 16 -1 (-1250 1750)(-1075 1750);
WIRE 16 -1 (-1075 1800)(-1075 1750);
WIRE 16 -1 (-1075 1850)(-1075 1800);
WIRE 16 -1 (-1250 1800)(-1075 1800);
WIRE 16 -1 (-1250 1850)(-1075 1850);
WIRE 16 -1 (-1075 1900)(-1075 1850);
WIRE 16 -1 (-1250 1900)(-1075 1900);
WIRE 16 -1 (-1075 1950)(-1075 1900);
WIRE 16 -1 (-1250 1950)(-1075 1950);
WIRE 16 -1 (-1075 2000)(-1075 1950);
WIRE 16 -1 (-1250 2000)(-1075 2000);
WIRE 16 -1 (-1075 2050)(-1075 2000);
WIRE 16 -1 (-1075 2100)(-1075 2050);
WIRE 16 -1 (-1250 2050)(-1075 2050);
WIRE 16 -1 (-1250 2100)(-1075 2100);
WIRE 16 -1 (-1075 2150)(-1075 2100);
WIRE 16 -1 (-1250 2150)(-1075 2150);
WIRE 16 -1 (-1075 2200)(-1075 2150);
WIRE 16 -1 (-1250 2200)(-1075 2200);
WIRE 16 -1 (-1075 2250)(-1075 2200);
WIRE 16 -1 (-1250 2250)(-1075 2250);
WIRE 16 -1 (-1075 2300)(-1075 2250);
WIRE 16 -1 (-1250 2300)(-1075 2300);
WIRE 16 -1 (-1075 2350)(-1075 2300);
WIRE 16 -1 (-1075 2400)(-1075 2350);
WIRE 16 -1 (-1250 2350)(-1075 2350);
WIRE 16 -1 (-1250 2400)(-1075 2400);
WIRE 16 -1 (-1075 2450)(-1075 2400);
WIRE 16 -1 (-1250 2450)(-1075 2450);
WIRE 16 -1 (-1075 2500)(-1075 2450);
WIRE 16 -1 (-1250 2500)(-1075 2500);
WIRE 16 -1 (-1075 2550)(-1075 2500);
WIRE 16 -1 (-1250 2550)(-1075 2550);
WIRE 16 -1 (-1075 2600)(-1075 2550);
WIRE 16 -1 (-1075 2650)(-1075 2600);
WIRE 16 -1 (-1250 2600)(-1075 2600);
WIRE 16 -1 (-1250 2650)(-1075 2650);
WIRE 16 -1 (-1075 2700)(-1075 2650);
WIRE 16 -1 (-1250 2700)(-1075 2700);
WIRE 16 -1 (-1075 2750)(-1075 2700);
WIRE 16 -1 (-1250 2750)(-1075 2750);
WIRE 16 -1 (-1075 2800)(-1075 2750);
WIRE 16 -1 (-1250 2800)(-1075 2800);
WIRE 16 -1 (-1075 2850)(-1075 2800);
WIRE 16 -1 (-1075 2900)(-1075 2850);
WIRE 16 -1 (-1250 2850)(-1075 2850);
WIRE 16 -1 (-1250 2900)(-1075 2900);
WIRE 16 -1 (-1075 2950)(-1075 2900);
WIRE 16 -1 (-1250 2950)(-1075 2950);
WIRE 16 -1 (-1075 3000)(-1075 2950);
WIRE 16 -1 (-1250 3000)(-1075 3000);
WIRE 16 -1 (-1075 3050)(-1075 3000);
WIRE 16 -1 (-1250 3050)(-1075 3050);
WIRE 16 -1 (-1075 3100)(-1075 3050);
WIRE 16 -1 (-1075 3150)(-1075 3100);
WIRE 16 -1 (-1250 3100)(-1075 3100);
WIRE 16 -1 (-1250 3150)(-1075 3150);
WIRE 16 -1 (-1075 3200)(-1075 3150);
WIRE 16 -1 (-1250 3200)(-1075 3200);
WIRE 16 -1 (-1075 3250)(-1075 3200);
WIRE 16 -1 (-1250 3250)(-1075 3250);
WIRE 16 -1 (-1075 3300)(-1075 3250);
WIRE 16 -1 (-1250 3300)(-1075 3300);
WIRE 16 -1 (-1075 3350)(-1075 3300);
WIRE 16 -1 (-1075 3400)(-1075 3350);
WIRE 16 -1 (-1250 3350)(-1075 3350);
WIRE 16 -1 (-1250 3400)(-1075 3400);
WIRE 16 -1 (-1075 3450)(-1075 3400);
WIRE 16 -1 (-1250 3450)(-1075 3450);
WIRE 16 -1 (-1075 3500)(-1075 3450);
WIRE 16 -1 (-1250 3500)(-1075 3500);
WIRE 16 -1 (-1075 3550)(-1075 3500);
WIRE 16 -1 (-1250 3550)(-1075 3550);
WIRE 16 -1 (-1075 3600)(-1075 3550);
WIRE 16 -1 (-1075 3650)(-1075 3600);
WIRE 16 -1 (-1250 3600)(-1075 3600);
WIRE 16 -1 (-1250 3650)(-1075 3650);
WIRE 16 -1 (-1075 3700)(-1075 3650);
WIRE 16 -1 (-1250 3700)(-1075 3700);
WIRE 16 -1 (-1075 3750)(-1075 3700);
WIRE 16 -1 (-1250 3750)(-1075 3750);
WIRE 16 -1 (-1075 3800)(-1075 3750);
WIRE 16 -1 (-1250 3800)(-1075 3800);
WIRE 16 -1 (-1075 3850)(-1075 3800);
WIRE 16 -1 (-1075 3900)(-1075 3850);
WIRE 16 -1 (-1250 3850)(-1075 3850);
WIRE 16 -1 (-1250 3900)(-1075 3900);
WIRE 16 -1 (-1075 3950)(-1075 3900);
WIRE 16 -1 (-1250 3950)(-1075 3950);
WIRE 16 -1 (-1075 4000)(-1075 3950);
WIRE 16 -1 (-1250 4000)(-1075 4000);
WIRE 16 -1 (-1075 4050)(-1075 4000);
WIRE 16 -1 (-1250 4050)(-1075 4050);
WIRE 16 -1 (-1075 4100)(-1075 4050);
WIRE 16 -1 (-1075 4150)(-1075 4100);
WIRE 16 -1 (-1250 4100)(-1075 4100);
WIRE 16 -1 (-1250 4150)(-1075 4150);
WIRE 16 -1 (-1075 4200)(-1075 4150);
WIRE 16 -1 (-1250 4200)(-1075 4200);
WIRE 16 -1 (-1075 4250)(-1075 4200);
WIRE 16 -1 (-1250 4250)(-1075 4250);
WIRE 16 -1 (-1075 4300)(-1075 4250);
WIRE 16 -1 (-1250 4300)(-1075 4300);
WIRE 16 -1 (-1075 4350)(-1075 4300);
WIRE 16 -1 (-1250 4350)(-1075 4350);
WIRE 16 -1 (-1075 4400)(-1075 4350);
WIRE 16 -1 (-1075 4450)(-1075 4400);
WIRE 16 -1 (-1250 4400)(-1075 4400);
WIRE 16 -1 (-1250 4450)(-1075 4450);
WIRE 16 -1 (-1075 4500)(-1075 4450);
WIRE 16 -1 (-1250 4500)(-1075 4500);
WIRE 16 -1 (-1075 4550)(-1075 4500);
WIRE 16 -1 (-1250 4550)(-1075 4550);
WIRE 16 -1 (-1075 4600)(-1075 4550);
WIRE 16 -1 (-1250 4600)(-1075 4600);
WIRE 16 -1 (-1075 4650)(-1075 4600);
WIRE 16 -1 (-1075 4700)(-1075 4650);
WIRE 16 -1 (-1250 4650)(-1075 4650);
WIRE 16 -1 (-1250 4700)(-1075 4700);
WIRE 16 -1 (-1075 4750)(-1075 4700);
WIRE 16 -1 (-1250 4750)(-1075 4750);
WIRE 16 -1 (-1075 4800)(-1075 4750);
WIRE 16 -1 (-1250 4800)(-1075 4800);
WIRE 16 -1 (-1075 4850)(-1075 4800);
WIRE 16 -1 (-1250 4850)(-1075 4850);
WIRE 16 -1 (-1075 4900)(-1075 4850);
WIRE 16 -1 (-1075 4950)(-1075 4900);
WIRE 16 -1 (-1250 4900)(-1075 4900);
WIRE 16 -1 (-1250 4950)(-1075 4950);
WIRE 16 -1 (-1075 5000)(-1075 4950);
WIRE 16 -1 (-1250 5000)(-1075 5000);
WIRE 16 -1 (-1075 5050)(-1075 5000);
WIRE 16 -1 (-1250 5050)(-1075 5050);
WIRE 16 -1 (-1075 5100)(-1075 5050);
WIRE 16 -1 (-1250 5100)(-1075 5100);
WIRE 16 -1 (-1075 5150)(-1075 5100);
WIRE 16 -1 (-1075 5200)(-1075 5150);
WIRE 16 -1 (-1250 5150)(-1075 5150);
WIRE 16 -1 (-1250 5200)(-1075 5200);
WIRE 16 -1 (-1075 5250)(-1075 5200);
WIRE 16 -1 (-1250 5250)(-1075 5250);
WIRE 16 -1 (-1075 5300)(-1075 5250);
WIRE 16 -1 (-1250 5300)(-1075 5300);
WIRE 16 -1 (-1075 5350)(-1075 5300);
WIRE 16 -1 (-1250 5350)(-1075 5350);
WIRE 16 -1 (-1075 5400)(-1075 5350);
WIRE 16 -1 (-1075 5450)(-1075 5400);
WIRE 16 -1 (-1250 5400)(-1075 5400);
WIRE 16 -1 (-1250 5450)(-1075 5450);
WIRE 16 -1 (-1075 5500)(-1075 5450);
WIRE 16 -1 (-1250 5500)(-1075 5500);
WIRE 16 -1 (-1075 5550)(-1075 5500);
WIRE 16 -1 (-1250 5550)(-1075 5550);
WIRE 16 -1 (-1075 5600)(-1075 5550);
WIRE 16 -1 (-1250 5600)(-1075 5600);
WIRE 16 -1 (-1075 5650)(-1075 5600);
WIRE 16 -1 (-1075 5700)(-1075 5650);
WIRE 16 -1 (-1250 5650)(-1075 5650);
WIRE 16 -1 (-1250 5700)(-1075 5700);
WIRE 16 -1 (-1075 5750)(-1075 5700);
WIRE 16 -1 (-1250 5750)(-1075 5750);
WIRE 16 -1 (-1075 5800)(-1075 5750);
WIRE 16 -1 (-1250 5800)(-1075 5800);
WIRE 16 -1 (-1075 5850)(-1075 5800);
WIRE 16 -1 (-1250 5850)(-1075 5850);
WIRE 16 -1 (-1075 5900)(-1075 5850);
WIRE 16 -1 (-1075 5950)(-1075 5900);
WIRE 16 -1 (-1250 5900)(-1075 5900);
WIRE 16 -1 (-1250 5950)(-1075 5950);
WIRE 16 -1 (-1075 6000)(-1075 5950);
WIRE 16 -1 (-1250 6000)(-1075 6000);
WIRE 16 -1 (-1075 6050)(-1075 6000);
WIRE 16 -1 (-1250 6050)(-1075 6050);
WIRE 16 -1 (-1075 6100)(-1075 6050);
WIRE 16 -1 (-1250 6100)(-1075 6100);
WIRE 16 -1 (-1075 6150)(-1075 6100);
WIRE 16 -1 (-1075 6200)(-1075 6150);
WIRE 16 -1 (-1250 6150)(-1075 6150);
WIRE 16 -1 (-1250 6200)(-1075 6200);
WIRE 16 -1 (-1075 6250)(-1075 6200);
WIRE 16 -1 (-1250 6250)(-1075 6250);
WIRE 16 -1 (-1075 6300)(-1075 6250);
WIRE 16 -1 (-1250 6300)(-1075 6300);
WIRE 16 -1 (-1075 6350)(-1075 6300);
WIRE 16 -1 (-1250 6350)(-1075 6350);
DOT 1 (-6675 5900);
DOT 1 (-6675 3750);
DOT 1 (-6675 3650);
DOT 1 (-7250 5150);
DOT 1 (-6675 4950);
DOT 1 (-5225 4150);
DOT 1 (-8700 550);
DOT 1 (-8700 600);
DOT 1 (-8700 650);
DOT 1 (-8700 700);
DOT 1 (-8700 750);
DOT 1 (-8700 800);
DOT 1 (-8700 850);
DOT 1 (-8700 900);
DOT 1 (-8700 950);
DOT 1 (-8700 1000);
DOT 1 (-8700 1050);
DOT 1 (-8700 1100);
DOT 1 (-8700 1150);
DOT 1 (-8700 1200);
DOT 1 (-8700 1250);
DOT 1 (-8700 1300);
DOT 1 (-8700 1350);
DOT 1 (-8700 1400);
DOT 1 (-8700 1450);
DOT 1 (-8700 1500);
DOT 1 (-8700 1550);
DOT 1 (-8700 1600);
DOT 1 (-8700 1700);
DOT 1 (-8700 1800);
DOT 1 (-8700 1750);
DOT 1 (-8700 1850);
DOT 1 (-8700 1900);
DOT 1 (-8700 1950);
DOT 1 (-8700 2000);
DOT 1 (-8700 2050);
DOT 1 (-8700 2100);
DOT 1 (-8700 2150);
DOT 1 (-8700 2200);
DOT 1 (-8700 2250);
DOT 1 (-8700 2300);
DOT 1 (-8700 2350);
DOT 1 (-8700 2400);
DOT 1 (-8700 2450);
DOT 1 (-8700 2500);
DOT 1 (-8700 2550);
DOT 1 (-8700 2600);
DOT 1 (-8700 2650);
DOT 1 (-8700 2700);
DOT 1 (-8700 2750);
DOT 1 (-8700 2800);
DOT 1 (-8700 2850);
DOT 1 (-8700 2900);
DOT 1 (-8700 2950);
DOT 1 (-8700 3000);
DOT 1 (-8700 3050);
DOT 1 (-8700 3100);
DOT 1 (-8700 3150);
DOT 1 (-8700 3250);
DOT 1 (-8700 3200);
DOT 1 (-8700 3300);
DOT 1 (-8700 3350);
DOT 1 (-8700 3400);
DOT 1 (-8700 3450);
DOT 1 (-8700 3500);
DOT 1 (-8700 3600);
DOT 1 (-8700 3550);
DOT 1 (-8700 3650);
DOT 1 (-8700 3700);
DOT 1 (-8700 3750);
DOT 1 (-8700 3800);
DOT 1 (-8700 3850);
DOT 1 (-8700 3900);
DOT 1 (-8700 3950);
DOT 1 (-8700 4000);
DOT 1 (-8700 4050);
DOT 1 (-8700 4150);
DOT 1 (-8700 4200);
DOT 1 (-8700 4250);
DOT 1 (-8700 4300);
DOT 1 (-8700 4350);
DOT 1 (-8700 4400);
DOT 1 (-8700 4450);
DOT 1 (-8700 4500);
DOT 1 (-8700 4550);
DOT 1 (-8700 4600);
DOT 1 (-8700 4650);
DOT 1 (-8700 4700);
DOT 1 (-8700 4750);
DOT 1 (-8700 4800);
DOT 1 (-8700 4850);
DOT 1 (-8700 4900);
DOT 1 (-8700 4950);
DOT 1 (-8700 5000);
DOT 1 (-8700 5050);
DOT 1 (-8700 5100);
DOT 1 (-8700 5150);
DOT 1 (-8700 5200);
DOT 1 (-8700 5250);
DOT 1 (-8700 5300);
DOT 1 (-8700 5350);
DOT 1 (-8700 5400);
DOT 1 (-8700 5450);
DOT 1 (-8700 5500);
DOT 1 (-8700 5550);
DOT 1 (-8700 5600);
DOT 1 (-8700 5650);
DOT 1 (-8700 5700);
DOT 1 (-8700 5750);
DOT 1 (-8700 5800);
DOT 1 (-8700 5850);
DOT 1 (-8700 5900);
DOT 1 (-8700 5950);
DOT 1 (-8700 6000);
DOT 1 (-8700 6050);
DOT 1 (-8700 6100);
DOT 1 (-8700 6150);
DOT 1 (-8700 6200);
DOT 1 (-8700 6250);
DOT 1 (-8700 6300);
DOT 1 (-8700 6350);
DOT 1 (-8700 6400);
DOT 1 (-7250 650);
DOT 1 (-7250 600);
DOT 1 (-7250 700);
DOT 1 (-7250 800);
DOT 1 (-7250 750);
DOT 1 (-7250 900);
DOT 1 (-7250 850);
DOT 1 (-7250 950);
DOT 1 (-7250 1050);
DOT 1 (-7250 1000);
DOT 1 (-6675 550);
DOT 1 (-6675 600);
DOT 1 (-6675 650);
DOT 1 (-6675 700);
DOT 1 (-6675 750);
DOT 1 (-6675 800);
DOT 1 (-6675 850);
DOT 1 (-6675 900);
DOT 1 (-6675 950);
DOT 1 (-6675 1050);
DOT 1 (-6675 1000);
DOT 1 (-7250 1100);
DOT 1 (-7250 1150);
DOT 1 (-7250 1200);
DOT 1 (-7250 1250);
DOT 1 (-7250 1300);
DOT 1 (-7250 1400);
DOT 1 (-7250 1450);
DOT 1 (-7250 1350);
DOT 1 (-7250 1500);
DOT 1 (-7250 1550);
DOT 1 (-7250 1600);
DOT 1 (-7250 1700);
DOT 1 (-7250 1750);
DOT 1 (-7250 1800);
DOT 1 (-7250 1850);
DOT 1 (-7250 1950);
DOT 1 (-7250 1900);
DOT 1 (-7250 2000);
DOT 1 (-7250 2050);
DOT 1 (-6675 1100);
DOT 1 (-6675 1150);
DOT 1 (-6675 1200);
DOT 1 (-6675 1250);
DOT 1 (-6675 1300);
DOT 1 (-6675 1350);
DOT 1 (-6675 1400);
DOT 1 (-6675 1450);
DOT 1 (-6675 1500);
DOT 1 (-6675 1550);
DOT 1 (-6675 1600);
DOT 1 (-6675 1650);
DOT 1 (-6675 1700);
DOT 1 (-6675 1750);
DOT 1 (-6675 1800);
DOT 1 (-6675 1850);
DOT 1 (-6675 1900);
DOT 1 (-6675 2050);
DOT 1 (-7250 2100);
DOT 1 (-7250 2200);
DOT 1 (-7250 2150);
DOT 1 (-7250 2350);
DOT 1 (-7250 2300);
DOT 1 (-7250 2250);
DOT 1 (-7250 2450);
DOT 1 (-7250 2400);
DOT 1 (-7250 2600);
DOT 1 (-7250 2550);
DOT 1 (-7250 2500);
DOT 1 (-7250 2700);
DOT 1 (-7250 2650);
DOT 1 (-7250 2750);
DOT 1 (-7250 2850);
DOT 1 (-7250 2800);
DOT 1 (-7250 2950);
DOT 1 (-7250 2900);
DOT 1 (-7250 3000);
DOT 1 (-7250 3100);
DOT 1 (-7250 3050);
DOT 1 (-6675 2150);
DOT 1 (-6675 2200);
DOT 1 (-6675 2250);
DOT 1 (-6675 2300);
DOT 1 (-6675 2350);
DOT 1 (-6675 2400);
DOT 1 (-6675 2450);
DOT 1 (-6675 2550);
DOT 1 (-6675 2500);
DOT 1 (-6675 2600);
DOT 1 (-6675 2650);
DOT 1 (-6675 2700);
DOT 1 (-6675 2750);
DOT 1 (-6675 2800);
DOT 1 (-6675 2850);
DOT 1 (-6675 2900);
DOT 1 (-6675 2950);
DOT 1 (-6675 3000);
DOT 1 (-6675 3100);
DOT 1 (-6675 3050);
DOT 1 (-7250 3150);
DOT 1 (-7250 3200);
DOT 1 (-7250 3250);
DOT 1 (-7250 3300);
DOT 1 (-7250 3350);
DOT 1 (-7250 3450);
DOT 1 (-7250 3500);
DOT 1 (-7250 3400);
DOT 1 (-7250 3550);
DOT 1 (-7250 3600);
DOT 1 (-7250 3700);
DOT 1 (-7250 3750);
DOT 1 (-7250 3650);
DOT 1 (-7250 3800);
DOT 1 (-7250 3850);
DOT 1 (-7250 3900);
DOT 1 (-7250 4000);
DOT 1 (-7250 3950);
DOT 1 (-7250 4050);
DOT 1 (-7250 4100);
DOT 1 (-6675 3150);
DOT 1 (-6675 3200);
DOT 1 (-6675 3250);
DOT 1 (-6675 3300);
DOT 1 (-6675 3350);
DOT 1 (-6675 3400);
DOT 1 (-6675 3450);
DOT 1 (-6675 3500);
DOT 1 (-6675 3600);
DOT 1 (-6675 3550);
DOT 1 (-6675 3700);
DOT 1 (-6675 3800);
DOT 1 (-6675 3850);
DOT 1 (-6675 3900);
DOT 1 (-6675 3950);
DOT 1 (-6675 4000);
DOT 1 (-6675 4050);
DOT 1 (-6675 4100);
DOT 1 (-5225 550);
DOT 1 (-5225 650);
DOT 1 (-5225 600);
DOT 1 (-5225 700);
DOT 1 (-5225 750);
DOT 1 (-5225 800);
DOT 1 (-5225 850);
DOT 1 (-5225 900);
DOT 1 (-5225 950);
DOT 1 (-5225 1000);
DOT 1 (-5225 1050);
DOT 1 (-4600 675);
DOT 1 (-4600 625);
DOT 1 (-4600 725);
DOT 1 (-4600 775);
DOT 1 (-4600 825);
DOT 1 (-4600 875);
DOT 1 (-4600 925);
DOT 1 (-4600 975);
DOT 1 (-4600 1025);
DOT 1 (-4600 1075);
DOT 1 (-5225 1100);
DOT 1 (-5225 1150);
DOT 1 (-5225 1200);
DOT 1 (-5225 1250);
DOT 1 (-5225 1300);
DOT 1 (-5225 1350);
DOT 1 (-5225 1400);
DOT 1 (-5225 1450);
DOT 1 (-5225 1500);
DOT 1 (-5225 1550);
DOT 1 (-5225 1600);
DOT 1 (-5225 1650);
DOT 1 (-5225 1700);
DOT 1 (-5225 1750);
DOT 1 (-5225 1800);
DOT 1 (-5225 1850);
DOT 1 (-5225 1900);
DOT 1 (-5225 1950);
DOT 1 (-5225 2000);
DOT 1 (-5225 2050);
DOT 1 (-4600 1125);
DOT 1 (-4600 1175);
DOT 1 (-4600 1225);
DOT 1 (-4600 1275);
DOT 1 (-4600 1325);
DOT 1 (-4600 1375);
DOT 1 (-4600 1425);
DOT 1 (-4600 1475);
DOT 1 (-4600 1525);
DOT 1 (-4600 1575);
DOT 1 (-4600 1625);
DOT 1 (-4600 1675);
DOT 1 (-4600 1725);
DOT 1 (-4600 1775);
DOT 1 (-4600 1825);
DOT 1 (-4600 1925);
DOT 1 (-4600 1875);
DOT 1 (-4600 1975);
DOT 1 (-4600 2025);
DOT 1 (-4600 2075);
DOT 1 (-5225 2100);
DOT 1 (-5225 2150);
DOT 1 (-5225 2200);
DOT 1 (-5225 2250);
DOT 1 (-5225 2300);
DOT 1 (-5225 2350);
DOT 1 (-5225 2400);
DOT 1 (-5225 2450);
DOT 1 (-5225 2500);
DOT 1 (-5225 2550);
DOT 1 (-5225 2600);
DOT 1 (-5225 2650);
DOT 1 (-5225 2700);
DOT 1 (-5225 2750);
DOT 1 (-5225 2800);
DOT 1 (-5225 2850);
DOT 1 (-5225 2900);
DOT 1 (-5225 2950);
DOT 1 (-5225 3000);
DOT 1 (-5225 3050);
DOT 1 (-5225 3100);
DOT 1 (-4600 2125);
DOT 1 (-4600 2175);
DOT 1 (-4600 2225);
DOT 1 (-4600 2275);
DOT 1 (-4600 2325);
DOT 1 (-4600 2375);
DOT 1 (-4600 2425);
DOT 1 (-4600 2475);
DOT 1 (-4600 2525);
DOT 1 (-4600 2575);
DOT 1 (-4600 2625);
DOT 1 (-4600 2675);
DOT 1 (-4600 2725);
DOT 1 (-4600 2775);
DOT 1 (-4600 2825);
DOT 1 (-4600 2875);
DOT 1 (-4600 2925);
DOT 1 (-4600 2975);
DOT 1 (-4600 3025);
DOT 1 (-4600 3075);
DOT 1 (-4600 3125);
DOT 1 (-5225 3150);
DOT 1 (-5225 3250);
DOT 1 (-5225 3200);
DOT 1 (-5225 3350);
DOT 1 (-5225 3300);
DOT 1 (-5225 3450);
DOT 1 (-5225 3500);
DOT 1 (-5225 3600);
DOT 1 (-5225 3550);
DOT 1 (-5225 3650);
DOT 1 (-5225 3700);
DOT 1 (-5225 3750);
DOT 1 (-5225 3800);
DOT 1 (-5225 3850);
DOT 1 (-5225 3900);
DOT 1 (-5225 3950);
DOT 1 (-5225 4000);
DOT 1 (-5225 4100);
DOT 1 (-5225 4050);
DOT 1 (-4600 3175);
DOT 1 (-4600 3225);
DOT 1 (-4600 3275);
DOT 1 (-4600 3325);
DOT 1 (-4600 3375);
DOT 1 (-4600 3425);
DOT 1 (-4600 3475);
DOT 1 (-4600 3525);
DOT 1 (-4600 3575);
DOT 1 (-4600 3625);
DOT 1 (-4600 3675);
DOT 1 (-4600 3725);
DOT 1 (-4600 3775);
DOT 1 (-4600 3825);
DOT 1 (-4600 3875);
DOT 1 (-4600 3925);
DOT 1 (-4600 3975);
DOT 1 (-4600 4025);
DOT 1 (-4600 4075);
DOT 1 (-4600 4125);
DOT 1 (-7250 4150);
DOT 1 (-6675 4150);
DOT 1 (-7250 4250);
DOT 1 (-7250 4200);
DOT 1 (-7250 4350);
DOT 1 (-7250 4400);
DOT 1 (-7250 4300);
DOT 1 (-7250 4450);
DOT 1 (-7250 4650);
DOT 1 (-7250 4550);
DOT 1 (-7250 4700);
DOT 1 (-7250 4750);
DOT 1 (-7250 4800);
DOT 1 (-7250 4850);
DOT 1 (-7250 4900);
DOT 1 (-7250 5000);
DOT 1 (-7250 4950);
DOT 1 (-7250 5050);
DOT 1 (-7250 5100);
DOT 1 (-6675 4200);
DOT 1 (-6675 4250);
DOT 1 (-6675 4300);
DOT 1 (-6675 4350);
DOT 1 (-6675 4400);
DOT 1 (-6675 4450);
DOT 1 (-6675 4500);
DOT 1 (-6675 4600);
DOT 1 (-6675 4550);
DOT 1 (-6675 4650);
DOT 1 (-6675 4700);
DOT 1 (-6675 4750);
DOT 1 (-6675 4800);
DOT 1 (-6675 4850);
DOT 1 (-6675 4900);
DOT 1 (-6675 5000);
DOT 1 (-6675 5050);
DOT 1 (-6675 5150);
DOT 1 (-6675 5100);
DOT 1 (-7250 5250);
DOT 1 (-7250 5200);
DOT 1 (-7250 5300);
DOT 1 (-7250 5400);
DOT 1 (-7250 5350);
DOT 1 (-7250 5500);
DOT 1 (-7250 5550);
DOT 1 (-7250 5450);
DOT 1 (-7250 5600);
DOT 1 (-7250 5650);
DOT 1 (-7250 5750);
DOT 1 (-7250 5800);
DOT 1 (-7250 5700);
DOT 1 (-7250 5850);
DOT 1 (-7250 5900);
DOT 1 (-7250 5950);
DOT 1 (-7250 6050);
DOT 1 (-7250 6000);
DOT 1 (-7250 6100);
DOT 1 (-7250 6150);
DOT 1 (-6675 5200);
DOT 1 (-6675 5250);
DOT 1 (-6675 5300);
DOT 1 (-6675 5350);
DOT 1 (-6675 5400);
DOT 1 (-6675 5450);
DOT 1 (-6675 5500);
DOT 1 (-6675 5550);
DOT 1 (-6675 5600);
DOT 1 (-6675 5650);
DOT 1 (-6675 5700);
DOT 1 (-6675 5750);
DOT 1 (-6675 5800);
DOT 1 (-6675 5850);
DOT 1 (-6675 6000);
DOT 1 (-6675 6050);
DOT 1 (-6675 6100);
DOT 1 (-6675 6150);
DOT 1 (-6675 6200);
DOT 1 (-7250 6200);
DOT 1 (-7250 6250);
DOT 1 (-7250 6400);
DOT 1 (-7250 6350);
DOT 1 (-6675 6300);
DOT 1 (-5225 4200);
DOT 1 (-5225 4250);
DOT 1 (-5225 4300);
DOT 1 (-5225 4350);
DOT 1 (-5225 4400);
DOT 1 (-5225 4500);
DOT 1 (-5225 4450);
DOT 1 (-5225 4550);
DOT 1 (-5225 4600);
DOT 1 (-5225 4650);
DOT 1 (-5225 4700);
DOT 1 (-5225 4750);
DOT 1 (-5225 4800);
DOT 1 (-5225 4850);
DOT 1 (-5225 4900);
DOT 1 (-5225 4950);
DOT 1 (-5225 5000);
DOT 1 (-5225 5050);
DOT 1 (-5225 5100);
DOT 1 (-5225 5150);
DOT 1 (-4600 4175);
DOT 1 (-4600 4225);
DOT 1 (-4600 4275);
DOT 1 (-4600 4325);
DOT 1 (-4600 4375);
DOT 1 (-4600 4425);
DOT 1 (-4600 4475);
DOT 1 (-4600 4525);
DOT 1 (-4600 4625);
DOT 1 (-4600 4575);
DOT 1 (-4600 4675);
DOT 1 (-4600 4725);
DOT 1 (-4600 4775);
DOT 1 (-4600 4825);
DOT 1 (-4600 4875);
DOT 1 (-4600 4925);
DOT 1 (-4600 4975);
DOT 1 (-4600 5025);
DOT 1 (-4600 5075);
DOT 1 (-4600 5125);
DOT 1 (-4600 5175);
DOT 1 (-5225 5200);
DOT 1 (-5225 5250);
DOT 1 (-5225 5300);
DOT 1 (-5225 5350);
DOT 1 (-5225 5400);
DOT 1 (-5225 5500);
DOT 1 (-5225 5550);
DOT 1 (-5225 5650);
DOT 1 (-5225 5600);
DOT 1 (-5225 5700);
DOT 1 (-5225 5750);
DOT 1 (-5225 5800);
DOT 1 (-5225 5850);
DOT 1 (-5225 5900);
DOT 1 (-5225 5950);
DOT 1 (-5225 6000);
DOT 1 (-5225 6050);
DOT 1 (-5225 6100);
DOT 1 (-5225 6150);
DOT 1 (-4600 5225);
DOT 1 (-4600 5275);
DOT 1 (-4600 5325);
DOT 1 (-4600 5375);
DOT 1 (-4600 5425);
DOT 1 (-4600 5475);
DOT 1 (-4600 5525);
DOT 1 (-4600 5575);
DOT 1 (-4600 5625);
DOT 1 (-4600 5675);
DOT 1 (-4600 5725);
DOT 1 (-4600 5775);
DOT 1 (-4600 5825);
DOT 1 (-4600 5875);
DOT 1 (-4600 5925);
DOT 1 (-4600 5975);
DOT 1 (-4600 6025);
DOT 1 (-4600 6075);
DOT 1 (-4600 6125);
DOT 1 (-4600 6175);
DOT 1 (-5225 6200);
DOT 1 (-5225 6250);
DOT 1 (-5225 6300);
DOT 1 (-4600 6225);
DOT 1 (-4600 6275);
DOT 1 (-3150 625);
DOT 1 (-3150 675);
DOT 1 (-3150 775);
DOT 1 (-3150 725);
DOT 1 (-3150 825);
DOT 1 (-3150 925);
DOT 1 (-3150 875);
DOT 1 (-3150 1025);
DOT 1 (-3150 975);
DOT 1 (-2525 550);
DOT 1 (-2525 600);
DOT 1 (-2525 650);
DOT 1 (-2525 700);
DOT 1 (-2525 750);
DOT 1 (-2525 800);
DOT 1 (-2525 850);
DOT 1 (-2525 900);
DOT 1 (-2525 950);
DOT 1 (-2525 1000);
DOT 1 (-2525 1050);
DOT 1 (-3150 1075);
DOT 1 (-3150 1175);
DOT 1 (-3150 1125);
DOT 1 (-3150 1325);
DOT 1 (-3150 1275);
DOT 1 (-3150 1225);
DOT 1 (-3150 1425);
DOT 1 (-3150 1375);
DOT 1 (-3150 1575);
DOT 1 (-3150 1525);
DOT 1 (-3150 1475);
DOT 1 (-3150 1625);
DOT 1 (-3150 1675);
DOT 1 (-3150 1725);
DOT 1 (-3150 1825);
DOT 1 (-3150 1775);
DOT 1 (-3150 1925);
DOT 1 (-3150 1875);
DOT 1 (-3150 1975);
DOT 1 (-3150 2075);
DOT 1 (-3150 2025);
DOT 1 (-2525 1100);
DOT 1 (-2525 1150);
DOT 1 (-2525 1200);
DOT 1 (-2525 1250);
DOT 1 (-2525 1300);
DOT 1 (-2525 1350);
DOT 1 (-2525 1400);
DOT 1 (-2525 1450);
DOT 1 (-2525 1500);
DOT 1 (-2525 1550);
DOT 1 (-2525 1600);
DOT 1 (-2525 1650);
DOT 1 (-2525 1700);
DOT 1 (-2525 1750);
DOT 1 (-2525 1800);
DOT 1 (-2525 1850);
DOT 1 (-2525 1900);
DOT 1 (-2525 1950);
DOT 1 (-2525 2000);
DOT 1 (-2525 2050);
DOT 1 (-2525 2100);
DOT 1 (-3150 2225);
DOT 1 (-3150 2175);
DOT 1 (-3150 2125);
DOT 1 (-3150 2325);
DOT 1 (-3150 2275);
DOT 1 (-3150 2425);
DOT 1 (-3150 2475);
DOT 1 (-3150 2375);
DOT 1 (-3150 2575);
DOT 1 (-3150 2525);
DOT 1 (-3150 2675);
DOT 1 (-3150 2725);
DOT 1 (-3150 2625);
DOT 1 (-3150 2775);
DOT 1 (-3150 2825);
DOT 1 (-3150 2875);
DOT 1 (-3150 2975);
DOT 1 (-3150 2925);
DOT 1 (-3150 3025);
DOT 1 (-3150 3075);
DOT 1 (-2525 2150);
DOT 1 (-2525 2200);
DOT 1 (-2525 2250);
DOT 1 (-2525 2300);
DOT 1 (-2525 2350);
DOT 1 (-2525 2400);
DOT 1 (-2525 2450);
DOT 1 (-2525 2500);
DOT 1 (-2525 2550);
DOT 1 (-2525 2600);
DOT 1 (-2525 2700);
DOT 1 (-2525 2650);
DOT 1 (-2525 2750);
DOT 1 (-2525 2800);
DOT 1 (-2525 2850);
DOT 1 (-2525 2900);
DOT 1 (-2525 2950);
DOT 1 (-2525 3000);
DOT 1 (-2525 3050);
DOT 1 (-2525 3100);
DOT 1 (-3150 3125);
DOT 1 (-3150 3225);
DOT 1 (-3150 3175);
DOT 1 (-3150 3375);
DOT 1 (-3150 3325);
DOT 1 (-3150 3275);
DOT 1 (-3150 3425);
DOT 1 (-3150 3475);
DOT 1 (-3150 3625);
DOT 1 (-3150 3575);
DOT 1 (-3150 3525);
DOT 1 (-3150 3675);
DOT 1 (-3150 3725);
DOT 1 (-3150 3775);
DOT 1 (-3150 3875);
DOT 1 (-3150 3825);
DOT 1 (-3150 3975);
DOT 1 (-3150 3925);
DOT 1 (-3150 4025);
DOT 1 (-3150 4125);
DOT 1 (-3150 4075);
DOT 1 (-2525 3150);
DOT 1 (-2525 3200);
DOT 1 (-2525 3250);
DOT 1 (-2525 3300);
DOT 1 (-2525 3350);
DOT 1 (-2525 3400);
DOT 1 (-2525 3450);
DOT 1 (-2525 3500);
DOT 1 (-2525 3550);
DOT 1 (-2525 3600);
DOT 1 (-2525 3650);
DOT 1 (-2525 3700);
DOT 1 (-2525 3750);
DOT 1 (-2525 3800);
DOT 1 (-2525 3850);
DOT 1 (-2525 3900);
DOT 1 (-2525 3950);
DOT 1 (-2525 4000);
DOT 1 (-2525 4050);
DOT 1 (-2525 4100);
DOT 1 (-1075 550);
DOT 1 (-1075 650);
DOT 1 (-1075 600);
DOT 1 (-1075 700);
DOT 1 (-1075 750);
DOT 1 (-1075 800);
DOT 1 (-1075 900);
DOT 1 (-1075 850);
DOT 1 (-1075 950);
DOT 1 (-1075 1000);
DOT 1 (-1075 1050);
DOT 1 (-1075 1100);
DOT 1 (-1075 1150);
DOT 1 (-1075 1200);
DOT 1 (-1075 1300);
DOT 1 (-1075 1250);
DOT 1 (-1075 1350);
DOT 1 (-1075 1400);
DOT 1 (-1075 1450);
DOT 1 (-1075 1550);
DOT 1 (-1075 1500);
DOT 1 (-1075 1650);
DOT 1 (-1075 1600);
DOT 1 (-1075 1700);
DOT 1 (-1075 1800);
DOT 1 (-1075 1750);
DOT 1 (-1075 1850);
DOT 1 (-1075 1900);
DOT 1 (-1075 1950);
DOT 1 (-1075 2050);
DOT 1 (-1075 2000);
DOT 1 (-1075 2100);
DOT 1 (-1075 2150);
DOT 1 (-1075 2200);
DOT 1 (-1075 2250);
DOT 1 (-1075 2300);
DOT 1 (-1075 2350);
DOT 1 (-1075 2450);
DOT 1 (-1075 2400);
DOT 1 (-1075 2500);
DOT 1 (-1075 2550);
DOT 1 (-1075 2600);
DOT 1 (-1075 2700);
DOT 1 (-1075 2650);
DOT 1 (-1075 2750);
DOT 1 (-1075 2800);
DOT 1 (-1075 2850);
DOT 1 (-1075 2950);
DOT 1 (-1075 2900);
DOT 1 (-1075 3000);
DOT 1 (-1075 3050);
DOT 1 (-1075 3100);
DOT 1 (-1075 3150);
DOT 1 (-1075 3200);
DOT 1 (-1075 3250);
DOT 1 (-1075 3300);
DOT 1 (-1075 3350);
DOT 1 (-1075 3400);
DOT 1 (-1075 3450);
DOT 1 (-1075 3500);
DOT 1 (-1075 3550);
DOT 1 (-1075 3600);
DOT 1 (-1075 3650);
DOT 1 (-1075 3700);
DOT 1 (-1075 3750);
DOT 1 (-1075 3850);
DOT 1 (-1075 3800);
DOT 1 (-1075 3900);
DOT 1 (-1075 3950);
DOT 1 (-1075 4000);
DOT 1 (-1075 4100);
DOT 1 (-1075 4050);
DOT 1 (-2525 4150);
DOT 1 (-1075 4150);
DOT 1 (-3150 4225);
DOT 1 (-3150 4175);
DOT 1 (-3150 4275);
DOT 1 (-3150 4375);
DOT 1 (-3150 4325);
DOT 1 (-3150 4525);
DOT 1 (-3150 4475);
DOT 1 (-3150 4425);
DOT 1 (-3150 4575);
DOT 1 (-3150 4625);
DOT 1 (-3150 4725);
DOT 1 (-3150 4775);
DOT 1 (-3150 4675);
DOT 1 (-3150 4875);
DOT 1 (-3150 4825);
DOT 1 (-3150 4925);
DOT 1 (-3150 5025);
DOT 1 (-3150 4975);
DOT 1 (-3150 5075);
DOT 1 (-3150 5125);
DOT 1 (-2525 4200);
DOT 1 (-2525 4250);
DOT 1 (-2525 4300);
DOT 1 (-2525 4350);
DOT 1 (-2525 4400);
DOT 1 (-2525 4450);
DOT 1 (-2525 4500);
DOT 1 (-2525 4550);
DOT 1 (-2525 4600);
DOT 1 (-2525 4650);
DOT 1 (-2525 4750);
DOT 1 (-2525 4700);
DOT 1 (-2525 4800);
DOT 1 (-2525 4850);
DOT 1 (-2525 4900);
DOT 1 (-2525 4950);
DOT 1 (-2525 5000);
DOT 1 (-2525 5050);
DOT 1 (-2525 5100);
DOT 1 (-2525 5150);
DOT 1 (-3150 5175);
DOT 1 (-3150 5275);
DOT 1 (-3150 5225);
DOT 1 (-3150 5425);
DOT 1 (-3150 5375);
DOT 1 (-3150 5325);
DOT 1 (-3150 5475);
DOT 1 (-3150 5525);
DOT 1 (-3150 5675);
DOT 1 (-3150 5625);
DOT 1 (-3150 5575);
DOT 1 (-3150 5725);
DOT 1 (-3150 5775);
DOT 1 (-3150 5925);
DOT 1 (-3150 5875);
DOT 1 (-3150 5825);
DOT 1 (-3150 6025);
DOT 1 (-3150 5975);
DOT 1 (-3150 6075);
DOT 1 (-3150 6175);
DOT 1 (-3150 6125);
DOT 1 (-2525 5250);
DOT 1 (-2525 5200);
DOT 1 (-2525 5300);
DOT 1 (-2525 5350);
DOT 1 (-2525 5400);
DOT 1 (-2525 5450);
DOT 1 (-2525 5500);
DOT 1 (-2525 5550);
DOT 1 (-2525 5600);
DOT 1 (-2525 5650);
DOT 1 (-2525 5700);
DOT 1 (-2525 5750);
DOT 1 (-2525 5800);
DOT 1 (-2525 5850);
DOT 1 (-2525 5900);
DOT 1 (-2525 5950);
DOT 1 (-2525 6000);
DOT 1 (-2525 6050);
DOT 1 (-2525 6100);
DOT 1 (-2525 6150);
DOT 1 (-2525 6200);
DOT 1 (-3150 6225);
DOT 1 (-3150 6275);
DOT 1 (-3150 6325);
DOT 1 (-3150 6375);
DOT 1 (-2525 6250);
DOT 1 (-2525 6300);
DOT 1 (-1075 4200);
DOT 1 (-1075 4250);
DOT 1 (-1075 4300);
DOT 1 (-1075 4350);
DOT 1 (-1075 4400);
DOT 1 (-1075 4450);
DOT 1 (-1075 4500);
DOT 1 (-1075 4550);
DOT 1 (-1075 4600);
DOT 1 (-1075 4650);
DOT 1 (-1075 4750);
DOT 1 (-1075 4700);
DOT 1 (-1075 4850);
DOT 1 (-1075 4800);
DOT 1 (-1075 4900);
DOT 1 (-1075 5000);
DOT 1 (-1075 4950);
DOT 1 (-1075 5050);
DOT 1 (-1075 5100);
DOT 1 (-1075 5150);
DOT 1 (-1075 5250);
DOT 1 (-1075 5200);
DOT 1 (-1075 5300);
DOT 1 (-1075 5350);
DOT 1 (-1075 5400);
DOT 1 (-1075 5450);
DOT 1 (-1075 5500);
DOT 1 (-1075 5550);
DOT 1 (-1075 5600);
DOT 1 (-1075 5650);
DOT 1 (-1075 5700);
DOT 1 (-1075 5750);
DOT 1 (-1075 5800);
DOT 1 (-1075 5900);
DOT 1 (-1075 5850);
DOT 1 (-1075 5950);
DOT 1 (-1075 6000);
DOT 1 (-1075 6050);
DOT 1 (-1075 6150);
DOT 1 (-1075 6100);
DOT 1 (-1075 6200);
DOT 1 (-1075 6250);
DOT 1 (-1075 6300);
DOT 1 (-8700 1650);
DOT 1 (-8700 4100);
DOT 1 (-5225 3400);
DOT 1 (-5225 5450);
DOT 1 (-7250 1650);
DOT 1 (-6675 1950);
DOT 1 (-6675 2000);
DOT 1 (-6675 2100);
DOT 1 (-7250 4500);
DOT 1 (-7250 4600);
DOT 1 (-6675 6350);
DOT 1 (-6675 6250);
DOT 1 (-6675 5950);
DOT 1 (-7250 6300);
QUIT
